FILE_TYPE = MACRO_DRAWING;
SET COLOR_WIRE YELLOW;
SET COLOR_PROP MONO;
SET COLOR_DOT WHITE;
SET COLOR_ARC YELLOW;
SET COLOR_BODY GREEN;
SET COLOR_NOTE MONO;
SET PROP_DISPLAY VALUE;
SET PAGE_NUMBER P82;
FORCEADD OFFPAGE..3
(1550 5150);
FORCEPROP 2 LAST $XR0 59 
J 0
(1764 5150);
DISPLAY 0.638298 (1764 5150);
PAINT MONO (1764 5150);
FORCEPROP 2 LAST $XR1 81 
J 0
(1854 5150);
DISPLAY 0.638298 (1854 5150);
PAINT MONO (1854 5150);
FORCEPROP 2 LAST CDS_LIB mstr_standard
J 0
(1550 5150);
DISPLAY 0.787234 (1550 5150);
PAINT MONO (1550 5150);
DISPLAY INVISIBLE (1550 5150);
FORCEPROP 1 LAST OFFPAGE TRUE
J 0
(1875 5025);
DISPLAY 0.936170 (1875 5025);
PAINT GREEN (1875 5025);
DISPLAY INVISIBLE (1875 5025);
FORCEPROP 1 LAST COMMENT_BODY TRUE
J 0
(1500 5050);
DISPLAY 0.936170 (1500 5050);
PAINT GREEN (1500 5050);
DISPLAY INVISIBLE (1500 5050);
FORCEPROP 2 LAST PATH I1
J 0
(1750 5225);
DISPLAY 0.787234 (1750 5225);
PAINT MONO (1750 5225);
DISPLAY INVISIBLE (1750 5225);
FORCEADD TAP..6
R 2
(650 4950);
FORCEPROP 3 LASTPIN (600 4950) SIG_NAME M_J_DQS_DP<15>
J 0
(610 4960);
DISPLAY 0.659574 (610 4960);
PAINT MONO (610 4960);
DISPLAY INVISIBLE (610 4960);
FORCEPROP 1 LASTPIN (600 4950) BN 15
J 2
(650 4960);
DISPLAY 0.617021 (650 4960);
PAINT PINK (650 4960);
FORCEPROP 2 LAST CDS_LIB mstr_standard
J 0
(650 4950);
DISPLAY 0.787234 (650 4950);
PAINT MONO (650 4950);
DISPLAY INVISIBLE (650 4950);
FORCEPROP 1 LAST BODY_TYPE PLUMBING
J 2
(650 4900);
DISPLAY 1.234043 (650 4900);
PAINT GREEN (650 4900);
DISPLAY INVISIBLE (650 4900);
FORCEPROP 1 LAST HDL_TAP TRUE
J 2
(325 4825);
DISPLAY 1.234043 (325 4825);
PAINT GREEN (325 4825);
DISPLAY INVISIBLE (325 4825);
FORCEPROP 1 LAST PATH I10
J 2
(650 4950);
DISPLAY 0.936170 (650 4950);
PAINT GREEN (650 4950);
DISPLAY INVISIBLE (650 4950);
FORCEADD TAP..6
R 2
(-1750 1900);
FORCEPROP 3 LASTPIN (-1800 1900) SIG_NAME M_J_DQ<5>
J 0
(-1790 1910);
DISPLAY 0.659574 (-1790 1910);
PAINT MONO (-1790 1910);
DISPLAY INVISIBLE (-1790 1910);
FORCEPROP 1 LASTPIN (-1800 1900) BN 5
J 2
(-1750 1910);
DISPLAY 0.617021 (-1750 1910);
PAINT PINK (-1750 1910);
FORCEPROP 2 LAST CDS_LIB mstr_standard
J 2
(-1750 1900);
DISPLAY 0.787234 (-1750 1900);
PAINT MONO (-1750 1900);
DISPLAY INVISIBLE (-1750 1900);
FORCEPROP 1 LAST BODY_TYPE PLUMBING
J 2
(-1750 1850);
DISPLAY 1.234043 (-1750 1850);
PAINT GREEN (-1750 1850);
DISPLAY INVISIBLE (-1750 1850);
FORCEPROP 1 LAST HDL_TAP TRUE
J 2
(-2075 1775);
DISPLAY 1.234043 (-2075 1775);
PAINT GREEN (-2075 1775);
DISPLAY INVISIBLE (-2075 1775);
FORCEPROP 1 LAST PATH I100
J 2
(-1750 1900);
DISPLAY 0.936170 (-1750 1900);
PAINT GREEN (-1750 1900);
DISPLAY INVISIBLE (-1750 1900);
FORCEADD TAP..6
R 2
(-1750 2000);
FORCEPROP 3 LASTPIN (-1800 2000) SIG_NAME M_J_DQ<7>
J 0
(-1790 2010);
DISPLAY 0.659574 (-1790 2010);
PAINT MONO (-1790 2010);
DISPLAY INVISIBLE (-1790 2010);
FORCEPROP 1 LASTPIN (-1800 2000) BN 7
J 2
(-1750 2010);
DISPLAY 0.617021 (-1750 2010);
PAINT PINK (-1750 2010);
FORCEPROP 2 LAST CDS_LIB mstr_standard
J 2
(-1750 2000);
DISPLAY 0.787234 (-1750 2000);
PAINT MONO (-1750 2000);
DISPLAY INVISIBLE (-1750 2000);
FORCEPROP 1 LAST BODY_TYPE PLUMBING
J 2
(-1750 1950);
DISPLAY 1.234043 (-1750 1950);
PAINT GREEN (-1750 1950);
DISPLAY INVISIBLE (-1750 1950);
FORCEPROP 1 LAST HDL_TAP TRUE
J 2
(-2075 1875);
DISPLAY 1.234043 (-2075 1875);
PAINT GREEN (-2075 1875);
DISPLAY INVISIBLE (-2075 1875);
FORCEPROP 1 LAST PATH I101
J 2
(-1750 2000);
DISPLAY 0.936170 (-1750 2000);
PAINT GREEN (-1750 2000);
DISPLAY INVISIBLE (-1750 2000);
FORCEADD TAP..6
R 2
(-1750 1950);
FORCEPROP 3 LASTPIN (-1800 1950) SIG_NAME M_J_DQ<6>
J 0
(-1790 1960);
DISPLAY 0.659574 (-1790 1960);
PAINT MONO (-1790 1960);
DISPLAY INVISIBLE (-1790 1960);
FORCEPROP 1 LASTPIN (-1800 1950) BN 6
J 2
(-1750 1960);
DISPLAY 0.617021 (-1750 1960);
PAINT PINK (-1750 1960);
FORCEPROP 2 LAST CDS_LIB mstr_standard
J 2
(-1750 1950);
DISPLAY 0.787234 (-1750 1950);
PAINT MONO (-1750 1950);
DISPLAY INVISIBLE (-1750 1950);
FORCEPROP 1 LAST BODY_TYPE PLUMBING
J 2
(-1750 1900);
DISPLAY 1.234043 (-1750 1900);
PAINT GREEN (-1750 1900);
DISPLAY INVISIBLE (-1750 1900);
FORCEPROP 1 LAST HDL_TAP TRUE
J 2
(-2075 1825);
DISPLAY 1.234043 (-2075 1825);
PAINT GREEN (-2075 1825);
DISPLAY INVISIBLE (-2075 1825);
FORCEPROP 1 LAST PATH I102
J 2
(-1750 1950);
DISPLAY 0.936170 (-1750 1950);
PAINT GREEN (-1750 1950);
DISPLAY INVISIBLE (-1750 1950);
FORCEADD TAP..6
R 2
(-1750 2050);
FORCEPROP 3 LASTPIN (-1800 2050) SIG_NAME M_J_DQ<8>
J 0
(-1790 2060);
DISPLAY 0.659574 (-1790 2060);
PAINT MONO (-1790 2060);
DISPLAY INVISIBLE (-1790 2060);
FORCEPROP 1 LASTPIN (-1800 2050) BN 8
J 2
(-1750 2060);
DISPLAY 0.617021 (-1750 2060);
PAINT PINK (-1750 2060);
FORCEPROP 2 LAST CDS_LIB mstr_standard
J 2
(-1750 2050);
DISPLAY 0.787234 (-1750 2050);
PAINT MONO (-1750 2050);
DISPLAY INVISIBLE (-1750 2050);
FORCEPROP 1 LAST BODY_TYPE PLUMBING
J 2
(-1750 2000);
DISPLAY 1.234043 (-1750 2000);
PAINT GREEN (-1750 2000);
DISPLAY INVISIBLE (-1750 2000);
FORCEPROP 1 LAST HDL_TAP TRUE
J 2
(-2075 1925);
DISPLAY 1.234043 (-2075 1925);
PAINT GREEN (-2075 1925);
DISPLAY INVISIBLE (-2075 1925);
FORCEPROP 1 LAST PATH I103
J 2
(-1750 2050);
DISPLAY 0.936170 (-1750 2050);
PAINT GREEN (-1750 2050);
DISPLAY INVISIBLE (-1750 2050);
FORCEADD TAP..6
R 2
(-1750 2100);
FORCEPROP 3 LASTPIN (-1800 2100) SIG_NAME M_J_DQ<9>
J 0
(-1790 2110);
DISPLAY 0.659574 (-1790 2110);
PAINT MONO (-1790 2110);
DISPLAY INVISIBLE (-1790 2110);
FORCEPROP 1 LASTPIN (-1800 2100) BN 9
J 2
(-1750 2110);
DISPLAY 0.617021 (-1750 2110);
PAINT PINK (-1750 2110);
FORCEPROP 2 LAST CDS_LIB mstr_standard
J 2
(-1750 2100);
DISPLAY 0.787234 (-1750 2100);
PAINT MONO (-1750 2100);
DISPLAY INVISIBLE (-1750 2100);
FORCEPROP 1 LAST BODY_TYPE PLUMBING
J 2
(-1750 2050);
DISPLAY 1.234043 (-1750 2050);
PAINT GREEN (-1750 2050);
DISPLAY INVISIBLE (-1750 2050);
FORCEPROP 1 LAST HDL_TAP TRUE
J 2
(-2075 1975);
DISPLAY 1.234043 (-2075 1975);
PAINT GREEN (-2075 1975);
DISPLAY INVISIBLE (-2075 1975);
FORCEPROP 1 LAST PATH I104
J 2
(-1750 2100);
DISPLAY 0.936170 (-1750 2100);
PAINT GREEN (-1750 2100);
DISPLAY INVISIBLE (-1750 2100);
FORCEADD TAP..6
R 2
(-1750 2150);
FORCEPROP 3 LASTPIN (-1800 2150) SIG_NAME M_J_DQ<10>
J 0
(-1790 2160);
DISPLAY 0.659574 (-1790 2160);
PAINT MONO (-1790 2160);
DISPLAY INVISIBLE (-1790 2160);
FORCEPROP 1 LASTPIN (-1800 2150) BN 10
J 2
(-1750 2160);
DISPLAY 0.617021 (-1750 2160);
PAINT PINK (-1750 2160);
FORCEPROP 2 LAST CDS_LIB mstr_standard
J 2
(-1750 2150);
DISPLAY 0.787234 (-1750 2150);
PAINT MONO (-1750 2150);
DISPLAY INVISIBLE (-1750 2150);
FORCEPROP 1 LAST BODY_TYPE PLUMBING
J 2
(-1750 2100);
DISPLAY 1.234043 (-1750 2100);
PAINT GREEN (-1750 2100);
DISPLAY INVISIBLE (-1750 2100);
FORCEPROP 1 LAST HDL_TAP TRUE
J 2
(-2075 2025);
DISPLAY 1.234043 (-2075 2025);
PAINT GREEN (-2075 2025);
DISPLAY INVISIBLE (-2075 2025);
FORCEPROP 1 LAST PATH I105
J 2
(-1750 2150);
DISPLAY 0.936170 (-1750 2150);
PAINT GREEN (-1750 2150);
DISPLAY INVISIBLE (-1750 2150);
FORCEADD TAP..6
R 2
(-1750 1800);
FORCEPROP 3 LASTPIN (-1800 1800) SIG_NAME M_J_DQ<3>
J 0
(-1790 1810);
DISPLAY 0.659574 (-1790 1810);
PAINT MONO (-1790 1810);
DISPLAY INVISIBLE (-1790 1810);
FORCEPROP 1 LASTPIN (-1800 1800) BN 3
J 2
(-1750 1810);
DISPLAY 0.617021 (-1750 1810);
PAINT PINK (-1750 1810);
FORCEPROP 2 LAST CDS_LIB mstr_standard
J 2
(-1750 1800);
DISPLAY 0.787234 (-1750 1800);
PAINT MONO (-1750 1800);
DISPLAY INVISIBLE (-1750 1800);
FORCEPROP 1 LAST BODY_TYPE PLUMBING
J 2
(-1750 1750);
DISPLAY 1.234043 (-1750 1750);
PAINT GREEN (-1750 1750);
DISPLAY INVISIBLE (-1750 1750);
FORCEPROP 1 LAST HDL_TAP TRUE
J 2
(-2075 1675);
DISPLAY 1.234043 (-2075 1675);
PAINT GREEN (-2075 1675);
DISPLAY INVISIBLE (-2075 1675);
FORCEPROP 1 LAST PATH I106
J 2
(-1750 1800);
DISPLAY 0.936170 (-1750 1800);
PAINT GREEN (-1750 1800);
DISPLAY INVISIBLE (-1750 1800);
FORCEADD TAP..6
R 2
(-1750 1850);
FORCEPROP 3 LASTPIN (-1800 1850) SIG_NAME M_J_DQ<4>
J 0
(-1790 1860);
DISPLAY 0.659574 (-1790 1860);
PAINT MONO (-1790 1860);
DISPLAY INVISIBLE (-1790 1860);
FORCEPROP 1 LASTPIN (-1800 1850) BN 4
J 2
(-1750 1860);
DISPLAY 0.617021 (-1750 1860);
PAINT PINK (-1750 1860);
FORCEPROP 2 LAST CDS_LIB mstr_standard
J 2
(-1750 1850);
DISPLAY 0.787234 (-1750 1850);
PAINT MONO (-1750 1850);
DISPLAY INVISIBLE (-1750 1850);
FORCEPROP 1 LAST BODY_TYPE PLUMBING
J 2
(-1750 1800);
DISPLAY 1.234043 (-1750 1800);
PAINT GREEN (-1750 1800);
DISPLAY INVISIBLE (-1750 1800);
FORCEPROP 1 LAST HDL_TAP TRUE
J 2
(-2075 1725);
DISPLAY 1.234043 (-2075 1725);
PAINT GREEN (-2075 1725);
DISPLAY INVISIBLE (-2075 1725);
FORCEPROP 1 LAST PATH I107
J 2
(-1750 1850);
DISPLAY 0.936170 (-1750 1850);
PAINT GREEN (-1750 1850);
DISPLAY INVISIBLE (-1750 1850);
FORCEADD TAP..6
R 2
(-1750 1700);
FORCEPROP 3 LASTPIN (-1800 1700) SIG_NAME M_J_DQ<1>
J 0
(-1790 1710);
DISPLAY 0.659574 (-1790 1710);
PAINT MONO (-1790 1710);
DISPLAY INVISIBLE (-1790 1710);
FORCEPROP 1 LASTPIN (-1800 1700) BN 1
J 2
(-1750 1710);
DISPLAY 0.617021 (-1750 1710);
PAINT PINK (-1750 1710);
FORCEPROP 2 LAST CDS_LIB mstr_standard
J 2
(-1750 1700);
DISPLAY 0.787234 (-1750 1700);
PAINT MONO (-1750 1700);
DISPLAY INVISIBLE (-1750 1700);
FORCEPROP 1 LAST BODY_TYPE PLUMBING
J 2
(-1750 1650);
DISPLAY 1.234043 (-1750 1650);
PAINT GREEN (-1750 1650);
DISPLAY INVISIBLE (-1750 1650);
FORCEPROP 1 LAST HDL_TAP TRUE
J 2
(-2075 1575);
DISPLAY 1.234043 (-2075 1575);
PAINT GREEN (-2075 1575);
DISPLAY INVISIBLE (-2075 1575);
FORCEPROP 1 LAST PATH I108
J 2
(-1750 1700);
DISPLAY 0.936170 (-1750 1700);
PAINT GREEN (-1750 1700);
DISPLAY INVISIBLE (-1750 1700);
FORCEADD TAP..6
R 2
(-1750 1650);
FORCEPROP 3 LASTPIN (-1800 1650) SIG_NAME M_J_DQ<0>
J 0
(-1790 1660);
DISPLAY 0.659574 (-1790 1660);
PAINT MONO (-1790 1660);
DISPLAY INVISIBLE (-1790 1660);
FORCEPROP 1 LASTPIN (-1800 1650) BN 0
J 2
(-1750 1660);
DISPLAY 0.617021 (-1750 1660);
PAINT PINK (-1750 1660);
FORCEPROP 2 LAST CDS_LIB mstr_standard
J 2
(-1750 1650);
DISPLAY 0.787234 (-1750 1650);
PAINT MONO (-1750 1650);
DISPLAY INVISIBLE (-1750 1650);
FORCEPROP 1 LAST BODY_TYPE PLUMBING
J 2
(-1750 1600);
DISPLAY 1.234043 (-1750 1600);
PAINT GREEN (-1750 1600);
DISPLAY INVISIBLE (-1750 1600);
FORCEPROP 1 LAST HDL_TAP TRUE
J 2
(-2075 1525);
DISPLAY 1.234043 (-2075 1525);
PAINT GREEN (-2075 1525);
DISPLAY INVISIBLE (-2075 1525);
FORCEPROP 1 LAST PATH I109
J 2
(-1750 1650);
DISPLAY 0.936170 (-1750 1650);
PAINT GREEN (-1750 1650);
DISPLAY INVISIBLE (-1750 1650);
FORCEADD TAP..6
R 2
(650 4850);
FORCEPROP 3 LASTPIN (600 4850) SIG_NAME M_J_DQS_DP<14>
J 0
(610 4860);
DISPLAY 0.659574 (610 4860);
PAINT MONO (610 4860);
DISPLAY INVISIBLE (610 4860);
FORCEPROP 1 LASTPIN (600 4850) BN 14
J 2
(650 4860);
DISPLAY 0.617021 (650 4860);
PAINT PINK (650 4860);
FORCEPROP 2 LAST CDS_LIB mstr_standard
J 0
(650 4850);
DISPLAY 0.787234 (650 4850);
PAINT MONO (650 4850);
DISPLAY INVISIBLE (650 4850);
FORCEPROP 1 LAST BODY_TYPE PLUMBING
J 2
(650 4800);
DISPLAY 1.234043 (650 4800);
PAINT GREEN (650 4800);
DISPLAY INVISIBLE (650 4800);
FORCEPROP 1 LAST HDL_TAP TRUE
J 2
(325 4725);
DISPLAY 1.234043 (325 4725);
PAINT GREEN (325 4725);
DISPLAY INVISIBLE (325 4725);
FORCEPROP 1 LAST PATH I11
J 2
(650 4850);
DISPLAY 0.936170 (650 4850);
PAINT GREEN (650 4850);
DISPLAY INVISIBLE (650 4850);
FORCEADD TAP..6
R 2
(-1750 1750);
FORCEPROP 3 LASTPIN (-1800 1750) SIG_NAME M_J_DQ<2>
J 0
(-1790 1760);
DISPLAY 0.659574 (-1790 1760);
PAINT MONO (-1790 1760);
DISPLAY INVISIBLE (-1790 1760);
FORCEPROP 1 LASTPIN (-1800 1750) BN 2
J 2
(-1750 1760);
DISPLAY 0.617021 (-1750 1760);
PAINT PINK (-1750 1760);
FORCEPROP 2 LAST CDS_LIB mstr_standard
J 2
(-1750 1750);
DISPLAY 0.787234 (-1750 1750);
PAINT MONO (-1750 1750);
DISPLAY INVISIBLE (-1750 1750);
FORCEPROP 1 LAST BODY_TYPE PLUMBING
J 2
(-1750 1700);
DISPLAY 1.234043 (-1750 1700);
PAINT GREEN (-1750 1700);
DISPLAY INVISIBLE (-1750 1700);
FORCEPROP 1 LAST HDL_TAP TRUE
J 2
(-2075 1625);
DISPLAY 1.234043 (-2075 1625);
PAINT GREEN (-2075 1625);
DISPLAY INVISIBLE (-2075 1625);
FORCEPROP 1 LAST PATH I110
J 2
(-1750 1750);
DISPLAY 0.936170 (-1750 1750);
PAINT GREEN (-1750 1750);
DISPLAY INVISIBLE (-1750 1750);
FORCEADD TAP..6
(-3250 4750);
FORCEPROP 3 LASTPIN (-3200 4750) SIG_NAME M_J_MA<16>
J 0
(-3190 4760);
DISPLAY 0.659574 (-3190 4760);
PAINT MONO (-3190 4760);
DISPLAY INVISIBLE (-3190 4760);
FORCEPROP 1 LASTPIN (-3200 4750) BN 16
J 0
(-3250 4760);
DISPLAY 0.617021 (-3250 4760);
PAINT PINK (-3250 4760);
FORCEPROP 2 LAST CDS_LIB mstr_standard
J 2
(-3250 4750);
DISPLAY 0.787234 (-3250 4750);
PAINT MONO (-3250 4750);
DISPLAY INVISIBLE (-3250 4750);
FORCEPROP 1 LAST BODY_TYPE PLUMBING
J 0
(-3250 4700);
DISPLAY 1.234043 (-3250 4700);
PAINT GREEN (-3250 4700);
DISPLAY INVISIBLE (-3250 4700);
FORCEPROP 1 LAST HDL_TAP TRUE
J 0
(-2925 4625);
DISPLAY 1.234043 (-2925 4625);
PAINT GREEN (-2925 4625);
DISPLAY INVISIBLE (-2925 4625);
FORCEPROP 1 LAST PATH I112
J 0
(-3250 4750);
DISPLAY 0.936170 (-3250 4750);
PAINT GREEN (-3250 4750);
DISPLAY INVISIBLE (-3250 4750);
FORCEADD TAP..6
(-3250 4800);
FORCEPROP 3 LASTPIN (-3200 4800) SIG_NAME M_J_MA<17>
J 0
(-3190 4810);
DISPLAY 0.659574 (-3190 4810);
PAINT MONO (-3190 4810);
DISPLAY INVISIBLE (-3190 4810);
FORCEPROP 1 LASTPIN (-3200 4800) BN 17
J 0
(-3250 4810);
DISPLAY 0.617021 (-3250 4810);
PAINT PINK (-3250 4810);
FORCEPROP 2 LAST CDS_LIB mstr_standard
J 0
(-3250 4800);
DISPLAY 0.787234 (-3250 4800);
PAINT MONO (-3250 4800);
DISPLAY INVISIBLE (-3250 4800);
FORCEPROP 1 LAST BODY_TYPE PLUMBING
J 0
(-3250 4750);
DISPLAY 1.234043 (-3250 4750);
PAINT GREEN (-3250 4750);
DISPLAY INVISIBLE (-3250 4750);
FORCEPROP 1 LAST HDL_TAP TRUE
J 0
(-2925 4675);
DISPLAY 1.234043 (-2925 4675);
PAINT GREEN (-2925 4675);
DISPLAY INVISIBLE (-2925 4675);
FORCEPROP 1 LAST PATH I113
J 0
(-3250 4800);
DISPLAY 0.936170 (-3250 4800);
PAINT GREEN (-3250 4800);
DISPLAY INVISIBLE (-3250 4800);
FORCEADD TAP..6
(-3250 4700);
FORCEPROP 3 LASTPIN (-3200 4700) SIG_NAME M_J_MA<15>
J 0
(-3190 4710);
DISPLAY 0.659574 (-3190 4710);
PAINT MONO (-3190 4710);
DISPLAY INVISIBLE (-3190 4710);
FORCEPROP 1 LASTPIN (-3200 4700) BN 15
J 0
(-3250 4710);
DISPLAY 0.617021 (-3250 4710);
PAINT PINK (-3250 4710);
FORCEPROP 2 LAST CDS_LIB mstr_standard
J 2
(-3250 4700);
DISPLAY 0.787234 (-3250 4700);
PAINT MONO (-3250 4700);
DISPLAY INVISIBLE (-3250 4700);
FORCEPROP 1 LAST BODY_TYPE PLUMBING
J 0
(-3250 4650);
DISPLAY 1.234043 (-3250 4650);
PAINT GREEN (-3250 4650);
DISPLAY INVISIBLE (-3250 4650);
FORCEPROP 1 LAST HDL_TAP TRUE
J 0
(-2925 4575);
DISPLAY 1.234043 (-2925 4575);
PAINT GREEN (-2925 4575);
DISPLAY INVISIBLE (-2925 4575);
FORCEPROP 1 LAST PATH I114
J 0
(-3250 4700);
DISPLAY 0.936170 (-3250 4700);
PAINT GREEN (-3250 4700);
DISPLAY INVISIBLE (-3250 4700);
FORCEADD TAP..6
(-3250 4650);
FORCEPROP 3 LASTPIN (-3200 4650) SIG_NAME M_J_MA<14>
J 0
(-3190 4660);
DISPLAY 0.659574 (-3190 4660);
PAINT MONO (-3190 4660);
DISPLAY INVISIBLE (-3190 4660);
FORCEPROP 1 LASTPIN (-3200 4650) BN 14
J 0
(-3250 4660);
DISPLAY 0.617021 (-3250 4660);
PAINT PINK (-3250 4660);
FORCEPROP 2 LAST CDS_LIB mstr_standard
J 2
(-3250 4650);
DISPLAY 0.787234 (-3250 4650);
PAINT MONO (-3250 4650);
DISPLAY INVISIBLE (-3250 4650);
FORCEPROP 1 LAST BODY_TYPE PLUMBING
J 0
(-3250 4600);
DISPLAY 1.234043 (-3250 4600);
PAINT GREEN (-3250 4600);
DISPLAY INVISIBLE (-3250 4600);
FORCEPROP 1 LAST HDL_TAP TRUE
J 0
(-2925 4525);
DISPLAY 1.234043 (-2925 4525);
PAINT GREEN (-2925 4525);
DISPLAY INVISIBLE (-2925 4525);
FORCEPROP 1 LAST PATH I115
J 0
(-3250 4650);
DISPLAY 0.936170 (-3250 4650);
PAINT GREEN (-3250 4650);
DISPLAY INVISIBLE (-3250 4650);
FORCEADD TAP..6
(-3250 4600);
FORCEPROP 3 LASTPIN (-3200 4600) SIG_NAME M_J_MA<13>
J 0
(-3190 4610);
DISPLAY 0.659574 (-3190 4610);
PAINT MONO (-3190 4610);
DISPLAY INVISIBLE (-3190 4610);
FORCEPROP 1 LASTPIN (-3200 4600) BN 13
J 0
(-3250 4610);
DISPLAY 0.617021 (-3250 4610);
PAINT PINK (-3250 4610);
FORCEPROP 2 LAST CDS_LIB mstr_standard
J 2
(-3250 4600);
DISPLAY 0.787234 (-3250 4600);
PAINT MONO (-3250 4600);
DISPLAY INVISIBLE (-3250 4600);
FORCEPROP 1 LAST BODY_TYPE PLUMBING
J 0
(-3250 4550);
DISPLAY 1.234043 (-3250 4550);
PAINT GREEN (-3250 4550);
DISPLAY INVISIBLE (-3250 4550);
FORCEPROP 1 LAST HDL_TAP TRUE
J 0
(-2925 4475);
DISPLAY 1.234043 (-2925 4475);
PAINT GREEN (-2925 4475);
DISPLAY INVISIBLE (-2925 4475);
FORCEPROP 1 LAST PATH I116
J 0
(-3250 4600);
DISPLAY 0.936170 (-3250 4600);
PAINT GREEN (-3250 4600);
DISPLAY INVISIBLE (-3250 4600);
FORCEADD TAP..6
(-3250 4500);
FORCEPROP 3 LASTPIN (-3200 4500) SIG_NAME M_J_MA<11>
J 0
(-3190 4510);
DISPLAY 0.659574 (-3190 4510);
PAINT MONO (-3190 4510);
DISPLAY INVISIBLE (-3190 4510);
FORCEPROP 1 LASTPIN (-3200 4500) BN 11
J 0
(-3250 4510);
DISPLAY 0.617021 (-3250 4510);
PAINT PINK (-3250 4510);
FORCEPROP 2 LAST CDS_LIB mstr_standard
J 2
(-3250 4500);
DISPLAY 0.787234 (-3250 4500);
PAINT MONO (-3250 4500);
DISPLAY INVISIBLE (-3250 4500);
FORCEPROP 1 LAST BODY_TYPE PLUMBING
J 0
(-3250 4450);
DISPLAY 1.234043 (-3250 4450);
PAINT GREEN (-3250 4450);
DISPLAY INVISIBLE (-3250 4450);
FORCEPROP 1 LAST HDL_TAP TRUE
J 0
(-2925 4375);
DISPLAY 1.234043 (-2925 4375);
PAINT GREEN (-2925 4375);
DISPLAY INVISIBLE (-2925 4375);
FORCEPROP 1 LAST PATH I117
J 0
(-3250 4500);
DISPLAY 0.936170 (-3250 4500);
PAINT GREEN (-3250 4500);
DISPLAY INVISIBLE (-3250 4500);
FORCEADD TAP..6
(-3250 4550);
FORCEPROP 3 LASTPIN (-3200 4550) SIG_NAME M_J_MA<12>
J 0
(-3190 4560);
DISPLAY 0.659574 (-3190 4560);
PAINT MONO (-3190 4560);
DISPLAY INVISIBLE (-3190 4560);
FORCEPROP 1 LASTPIN (-3200 4550) BN 12
J 0
(-3250 4560);
DISPLAY 0.617021 (-3250 4560);
PAINT PINK (-3250 4560);
FORCEPROP 2 LAST CDS_LIB mstr_standard
J 2
(-3250 4550);
DISPLAY 0.787234 (-3250 4550);
PAINT MONO (-3250 4550);
DISPLAY INVISIBLE (-3250 4550);
FORCEPROP 1 LAST BODY_TYPE PLUMBING
J 0
(-3250 4500);
DISPLAY 1.234043 (-3250 4500);
PAINT GREEN (-3250 4500);
DISPLAY INVISIBLE (-3250 4500);
FORCEPROP 1 LAST HDL_TAP TRUE
J 0
(-2925 4425);
DISPLAY 1.234043 (-2925 4425);
PAINT GREEN (-2925 4425);
DISPLAY INVISIBLE (-2925 4425);
FORCEPROP 1 LAST PATH I118
J 0
(-3250 4550);
DISPLAY 0.936170 (-3250 4550);
PAINT GREEN (-3250 4550);
DISPLAY INVISIBLE (-3250 4550);
FORCEADD TAP..6
(-3250 4450);
FORCEPROP 3 LASTPIN (-3200 4450) SIG_NAME M_J_MA<10>
J 0
(-3190 4460);
DISPLAY 0.659574 (-3190 4460);
PAINT MONO (-3190 4460);
DISPLAY INVISIBLE (-3190 4460);
FORCEPROP 1 LASTPIN (-3200 4450) BN 10
J 0
(-3250 4460);
DISPLAY 0.617021 (-3250 4460);
PAINT PINK (-3250 4460);
FORCEPROP 2 LAST CDS_LIB mstr_standard
J 2
(-3250 4450);
DISPLAY 0.787234 (-3250 4450);
PAINT MONO (-3250 4450);
DISPLAY INVISIBLE (-3250 4450);
FORCEPROP 1 LAST BODY_TYPE PLUMBING
J 0
(-3250 4400);
DISPLAY 1.234043 (-3250 4400);
PAINT GREEN (-3250 4400);
DISPLAY INVISIBLE (-3250 4400);
FORCEPROP 1 LAST HDL_TAP TRUE
J 0
(-2925 4325);
DISPLAY 1.234043 (-2925 4325);
PAINT GREEN (-2925 4325);
DISPLAY INVISIBLE (-2925 4325);
FORCEPROP 1 LAST PATH I119
J 0
(-3250 4450);
DISPLAY 0.936170 (-3250 4450);
PAINT GREEN (-3250 4450);
DISPLAY INVISIBLE (-3250 4450);
FORCEADD TAP..6
R 2
(650 4750);
FORCEPROP 3 LASTPIN (600 4750) SIG_NAME M_J_DQS_DP<13>
J 0
(610 4760);
DISPLAY 0.659574 (610 4760);
PAINT MONO (610 4760);
DISPLAY INVISIBLE (610 4760);
FORCEPROP 1 LASTPIN (600 4750) BN 13
J 2
(650 4760);
DISPLAY 0.617021 (650 4760);
PAINT PINK (650 4760);
FORCEPROP 2 LAST CDS_LIB mstr_standard
J 0
(650 4750);
DISPLAY 0.787234 (650 4750);
PAINT MONO (650 4750);
DISPLAY INVISIBLE (650 4750);
FORCEPROP 1 LAST BODY_TYPE PLUMBING
J 2
(650 4700);
DISPLAY 1.234043 (650 4700);
PAINT GREEN (650 4700);
DISPLAY INVISIBLE (650 4700);
FORCEPROP 1 LAST HDL_TAP TRUE
J 2
(325 4625);
DISPLAY 1.234043 (325 4625);
PAINT GREEN (325 4625);
DISPLAY INVISIBLE (325 4625);
FORCEPROP 1 LAST PATH I12
J 2
(650 4750);
DISPLAY 0.936170 (650 4750);
PAINT GREEN (650 4750);
DISPLAY INVISIBLE (650 4750);
FORCEADD TAP..6
(-3250 4400);
FORCEPROP 3 LASTPIN (-3200 4400) SIG_NAME M_J_MA<9>
J 0
(-3190 4410);
DISPLAY 0.659574 (-3190 4410);
PAINT MONO (-3190 4410);
DISPLAY INVISIBLE (-3190 4410);
FORCEPROP 1 LASTPIN (-3200 4400) BN 9
J 0
(-3250 4410);
DISPLAY 0.617021 (-3250 4410);
PAINT PINK (-3250 4410);
FORCEPROP 2 LAST CDS_LIB mstr_standard
J 2
(-3250 4400);
DISPLAY 0.787234 (-3250 4400);
PAINT MONO (-3250 4400);
DISPLAY INVISIBLE (-3250 4400);
FORCEPROP 1 LAST BODY_TYPE PLUMBING
J 0
(-3250 4350);
DISPLAY 1.234043 (-3250 4350);
PAINT GREEN (-3250 4350);
DISPLAY INVISIBLE (-3250 4350);
FORCEPROP 1 LAST HDL_TAP TRUE
J 0
(-2925 4275);
DISPLAY 1.234043 (-2925 4275);
PAINT GREEN (-2925 4275);
DISPLAY INVISIBLE (-2925 4275);
FORCEPROP 1 LAST PATH I120
J 0
(-3250 4400);
DISPLAY 0.936170 (-3250 4400);
PAINT GREEN (-3250 4400);
DISPLAY INVISIBLE (-3250 4400);
FORCEADD TAP..6
(-3250 4350);
FORCEPROP 3 LASTPIN (-3200 4350) SIG_NAME M_J_MA<8>
J 0
(-3190 4360);
DISPLAY 0.659574 (-3190 4360);
PAINT MONO (-3190 4360);
DISPLAY INVISIBLE (-3190 4360);
FORCEPROP 1 LASTPIN (-3200 4350) BN 8
J 0
(-3250 4360);
DISPLAY 0.617021 (-3250 4360);
PAINT PINK (-3250 4360);
FORCEPROP 2 LAST CDS_LIB mstr_standard
J 2
(-3250 4350);
DISPLAY 0.787234 (-3250 4350);
PAINT MONO (-3250 4350);
DISPLAY INVISIBLE (-3250 4350);
FORCEPROP 1 LAST BODY_TYPE PLUMBING
J 0
(-3250 4300);
DISPLAY 1.234043 (-3250 4300);
PAINT GREEN (-3250 4300);
DISPLAY INVISIBLE (-3250 4300);
FORCEPROP 1 LAST HDL_TAP TRUE
J 0
(-2925 4225);
DISPLAY 1.234043 (-2925 4225);
PAINT GREEN (-2925 4225);
DISPLAY INVISIBLE (-2925 4225);
FORCEPROP 1 LAST PATH I121
J 0
(-3250 4350);
DISPLAY 0.936170 (-3250 4350);
PAINT GREEN (-3250 4350);
DISPLAY INVISIBLE (-3250 4350);
FORCEADD TAP..6
(-3250 4250);
FORCEPROP 3 LASTPIN (-3200 4250) SIG_NAME M_J_MA<6>
J 0
(-3190 4260);
DISPLAY 0.659574 (-3190 4260);
PAINT MONO (-3190 4260);
DISPLAY INVISIBLE (-3190 4260);
FORCEPROP 1 LASTPIN (-3200 4250) BN 6
J 0
(-3250 4260);
DISPLAY 0.617021 (-3250 4260);
PAINT PINK (-3250 4260);
FORCEPROP 2 LAST CDS_LIB mstr_standard
J 2
(-3250 4250);
DISPLAY 0.787234 (-3250 4250);
PAINT MONO (-3250 4250);
DISPLAY INVISIBLE (-3250 4250);
FORCEPROP 1 LAST BODY_TYPE PLUMBING
J 0
(-3250 4200);
DISPLAY 1.234043 (-3250 4200);
PAINT GREEN (-3250 4200);
DISPLAY INVISIBLE (-3250 4200);
FORCEPROP 1 LAST HDL_TAP TRUE
J 0
(-2925 4125);
DISPLAY 1.234043 (-2925 4125);
PAINT GREEN (-2925 4125);
DISPLAY INVISIBLE (-2925 4125);
FORCEPROP 1 LAST PATH I122
J 0
(-3250 4250);
DISPLAY 0.936170 (-3250 4250);
PAINT GREEN (-3250 4250);
DISPLAY INVISIBLE (-3250 4250);
FORCEADD TAP..6
(-3250 4300);
FORCEPROP 3 LASTPIN (-3200 4300) SIG_NAME M_J_MA<7>
J 0
(-3190 4310);
DISPLAY 0.659574 (-3190 4310);
PAINT MONO (-3190 4310);
DISPLAY INVISIBLE (-3190 4310);
FORCEPROP 1 LASTPIN (-3200 4300) BN 7
J 0
(-3250 4310);
DISPLAY 0.617021 (-3250 4310);
PAINT PINK (-3250 4310);
FORCEPROP 2 LAST CDS_LIB mstr_standard
J 2
(-3250 4300);
DISPLAY 0.787234 (-3250 4300);
PAINT MONO (-3250 4300);
DISPLAY INVISIBLE (-3250 4300);
FORCEPROP 1 LAST BODY_TYPE PLUMBING
J 0
(-3250 4250);
DISPLAY 1.234043 (-3250 4250);
PAINT GREEN (-3250 4250);
DISPLAY INVISIBLE (-3250 4250);
FORCEPROP 1 LAST HDL_TAP TRUE
J 0
(-2925 4175);
DISPLAY 1.234043 (-2925 4175);
PAINT GREEN (-2925 4175);
DISPLAY INVISIBLE (-2925 4175);
FORCEPROP 1 LAST PATH I123
J 0
(-3250 4300);
DISPLAY 0.936170 (-3250 4300);
PAINT GREEN (-3250 4300);
DISPLAY INVISIBLE (-3250 4300);
FORCEADD TAP..6
(-3250 4200);
FORCEPROP 3 LASTPIN (-3200 4200) SIG_NAME M_J_MA<5>
J 0
(-3190 4210);
DISPLAY 0.659574 (-3190 4210);
PAINT MONO (-3190 4210);
DISPLAY INVISIBLE (-3190 4210);
FORCEPROP 1 LASTPIN (-3200 4200) BN 5
J 0
(-3250 4210);
DISPLAY 0.617021 (-3250 4210);
PAINT PINK (-3250 4210);
FORCEPROP 2 LAST CDS_LIB mstr_standard
J 2
(-3250 4200);
DISPLAY 0.787234 (-3250 4200);
PAINT MONO (-3250 4200);
DISPLAY INVISIBLE (-3250 4200);
FORCEPROP 1 LAST BODY_TYPE PLUMBING
J 0
(-3250 4150);
DISPLAY 1.234043 (-3250 4150);
PAINT GREEN (-3250 4150);
DISPLAY INVISIBLE (-3250 4150);
FORCEPROP 1 LAST HDL_TAP TRUE
J 0
(-2925 4075);
DISPLAY 1.234043 (-2925 4075);
PAINT GREEN (-2925 4075);
DISPLAY INVISIBLE (-2925 4075);
FORCEPROP 1 LAST PATH I124
J 0
(-3250 4200);
DISPLAY 0.936170 (-3250 4200);
PAINT GREEN (-3250 4200);
DISPLAY INVISIBLE (-3250 4200);
FORCEADD TAP..6
(-3250 4100);
FORCEPROP 3 LASTPIN (-3200 4100) SIG_NAME M_J_MA<3>
J 0
(-3190 4110);
DISPLAY 0.659574 (-3190 4110);
PAINT MONO (-3190 4110);
DISPLAY INVISIBLE (-3190 4110);
FORCEPROP 1 LASTPIN (-3200 4100) BN 3
J 0
(-3250 4110);
DISPLAY 0.617021 (-3250 4110);
PAINT PINK (-3250 4110);
FORCEPROP 2 LAST CDS_LIB mstr_standard
J 2
(-3250 4100);
DISPLAY 0.787234 (-3250 4100);
PAINT MONO (-3250 4100);
DISPLAY INVISIBLE (-3250 4100);
FORCEPROP 1 LAST BODY_TYPE PLUMBING
J 0
(-3250 4050);
DISPLAY 1.234043 (-3250 4050);
PAINT GREEN (-3250 4050);
DISPLAY INVISIBLE (-3250 4050);
FORCEPROP 1 LAST HDL_TAP TRUE
J 0
(-2925 3975);
DISPLAY 1.234043 (-2925 3975);
PAINT GREEN (-2925 3975);
DISPLAY INVISIBLE (-2925 3975);
FORCEPROP 1 LAST PATH I125
J 0
(-3250 4100);
DISPLAY 0.936170 (-3250 4100);
PAINT GREEN (-3250 4100);
DISPLAY INVISIBLE (-3250 4100);
FORCEADD TAP..6
(-3250 4150);
FORCEPROP 3 LASTPIN (-3200 4150) SIG_NAME M_J_MA<4>
J 0
(-3190 4160);
DISPLAY 0.659574 (-3190 4160);
PAINT MONO (-3190 4160);
DISPLAY INVISIBLE (-3190 4160);
FORCEPROP 1 LASTPIN (-3200 4150) BN 4
J 0
(-3250 4160);
DISPLAY 0.617021 (-3250 4160);
PAINT PINK (-3250 4160);
FORCEPROP 2 LAST CDS_LIB mstr_standard
J 2
(-3250 4150);
DISPLAY 0.787234 (-3250 4150);
PAINT MONO (-3250 4150);
DISPLAY INVISIBLE (-3250 4150);
FORCEPROP 1 LAST BODY_TYPE PLUMBING
J 0
(-3250 4100);
DISPLAY 1.234043 (-3250 4100);
PAINT GREEN (-3250 4100);
DISPLAY INVISIBLE (-3250 4100);
FORCEPROP 1 LAST HDL_TAP TRUE
J 0
(-2925 4025);
DISPLAY 1.234043 (-2925 4025);
PAINT GREEN (-2925 4025);
DISPLAY INVISIBLE (-2925 4025);
FORCEPROP 1 LAST PATH I126
J 0
(-3250 4150);
DISPLAY 0.936170 (-3250 4150);
PAINT GREEN (-3250 4150);
DISPLAY INVISIBLE (-3250 4150);
FORCEADD TAP..6
(-3250 4050);
FORCEPROP 3 LASTPIN (-3200 4050) SIG_NAME M_J_MA<2>
J 0
(-3190 4060);
DISPLAY 0.659574 (-3190 4060);
PAINT MONO (-3190 4060);
DISPLAY INVISIBLE (-3190 4060);
FORCEPROP 1 LASTPIN (-3200 4050) BN 2
J 0
(-3250 4060);
DISPLAY 0.617021 (-3250 4060);
PAINT PINK (-3250 4060);
FORCEPROP 2 LAST CDS_LIB mstr_standard
J 2
(-3250 4050);
DISPLAY 0.787234 (-3250 4050);
PAINT MONO (-3250 4050);
DISPLAY INVISIBLE (-3250 4050);
FORCEPROP 1 LAST BODY_TYPE PLUMBING
J 0
(-3250 4000);
DISPLAY 1.234043 (-3250 4000);
PAINT GREEN (-3250 4000);
DISPLAY INVISIBLE (-3250 4000);
FORCEPROP 1 LAST HDL_TAP TRUE
J 0
(-2925 3925);
DISPLAY 1.234043 (-2925 3925);
PAINT GREEN (-2925 3925);
DISPLAY INVISIBLE (-2925 3925);
FORCEPROP 1 LAST PATH I127
J 0
(-3250 4050);
DISPLAY 0.936170 (-3250 4050);
PAINT GREEN (-3250 4050);
DISPLAY INVISIBLE (-3250 4050);
FORCEADD TAP..6
(-3250 3950);
FORCEPROP 3 LASTPIN (-3200 3950) SIG_NAME M_J_MA<0>
J 0
(-3190 3960);
DISPLAY 0.659574 (-3190 3960);
PAINT MONO (-3190 3960);
DISPLAY INVISIBLE (-3190 3960);
FORCEPROP 1 LASTPIN (-3200 3950) BN 0
J 0
(-3250 3960);
DISPLAY 0.617021 (-3250 3960);
PAINT PINK (-3250 3960);
FORCEPROP 2 LAST CDS_LIB mstr_standard
J 2
(-3250 3950);
DISPLAY 0.787234 (-3250 3950);
PAINT MONO (-3250 3950);
DISPLAY INVISIBLE (-3250 3950);
FORCEPROP 1 LAST BODY_TYPE PLUMBING
J 0
(-3250 3900);
DISPLAY 1.234043 (-3250 3900);
PAINT GREEN (-3250 3900);
DISPLAY INVISIBLE (-3250 3900);
FORCEPROP 1 LAST HDL_TAP TRUE
J 0
(-2925 3825);
DISPLAY 1.234043 (-2925 3825);
PAINT GREEN (-2925 3825);
DISPLAY INVISIBLE (-2925 3825);
FORCEPROP 1 LAST PATH I128
J 0
(-3250 3950);
DISPLAY 0.936170 (-3250 3950);
PAINT GREEN (-3250 3950);
DISPLAY INVISIBLE (-3250 3950);
FORCEADD TAP..6
(-3250 4000);
FORCEPROP 3 LASTPIN (-3200 4000) SIG_NAME M_J_MA<1>
J 0
(-3190 4010);
DISPLAY 0.659574 (-3190 4010);
PAINT MONO (-3190 4010);
DISPLAY INVISIBLE (-3190 4010);
FORCEPROP 1 LASTPIN (-3200 4000) BN 1
J 0
(-3250 4010);
DISPLAY 0.617021 (-3250 4010);
PAINT PINK (-3250 4010);
FORCEPROP 2 LAST CDS_LIB mstr_standard
J 2
(-3250 4000);
DISPLAY 0.787234 (-3250 4000);
PAINT MONO (-3250 4000);
DISPLAY INVISIBLE (-3250 4000);
FORCEPROP 1 LAST BODY_TYPE PLUMBING
J 0
(-3250 3950);
DISPLAY 1.234043 (-3250 3950);
PAINT GREEN (-3250 3950);
DISPLAY INVISIBLE (-3250 3950);
FORCEPROP 1 LAST HDL_TAP TRUE
J 0
(-2925 3875);
DISPLAY 1.234043 (-2925 3875);
PAINT GREEN (-2925 3875);
DISPLAY INVISIBLE (-2925 3875);
FORCEPROP 1 LAST PATH I129
J 0
(-3250 4000);
DISPLAY 0.936170 (-3250 4000);
PAINT GREEN (-3250 4000);
DISPLAY INVISIBLE (-3250 4000);
FORCEADD TAP..6
R 2
(650 4650);
FORCEPROP 3 LASTPIN (600 4650) SIG_NAME M_J_DQS_DP<12>
J 0
(610 4660);
DISPLAY 0.659574 (610 4660);
PAINT MONO (610 4660);
DISPLAY INVISIBLE (610 4660);
FORCEPROP 1 LASTPIN (600 4650) BN 12
J 2
(650 4660);
DISPLAY 0.617021 (650 4660);
PAINT PINK (650 4660);
FORCEPROP 2 LAST CDS_LIB mstr_standard
J 0
(650 4650);
DISPLAY 0.787234 (650 4650);
PAINT MONO (650 4650);
DISPLAY INVISIBLE (650 4650);
FORCEPROP 1 LAST BODY_TYPE PLUMBING
J 2
(650 4600);
DISPLAY 1.234043 (650 4600);
PAINT GREEN (650 4600);
DISPLAY INVISIBLE (650 4600);
FORCEPROP 1 LAST HDL_TAP TRUE
J 2
(325 4525);
DISPLAY 1.234043 (325 4525);
PAINT GREEN (325 4525);
DISPLAY INVISIBLE (325 4525);
FORCEPROP 1 LAST PATH I13
J 2
(650 4650);
DISPLAY 0.936170 (650 4650);
PAINT GREEN (650 4650);
DISPLAY INVISIBLE (650 4650);
FORCEADD OFFPAGE..1
(-3900 4850);
FORCEPROP 2 LAST $XR0 59 
J 0
(-4121 4850);
DISPLAY 0.638298 (-4121 4850);
PAINT MONO (-4121 4850);
FORCEPROP 2 LAST $XR1 81 
J 0
(-4211 4850);
DISPLAY 0.638298 (-4211 4850);
PAINT MONO (-4211 4850);
FORCEPROP 2 LAST CDS_LIB mstr_standard
J 0
(-3900 4850);
DISPLAY 0.787234 (-3900 4850);
PAINT MONO (-3900 4850);
DISPLAY INVISIBLE (-3900 4850);
FORCEPROP 1 LAST OFFPAGE TRUE
J 0
(-3575 4725);
DISPLAY 0.936170 (-3575 4725);
PAINT GREEN (-3575 4725);
DISPLAY INVISIBLE (-3575 4725);
FORCEPROP 1 LAST COMMENT_BODY TRUE
J 0
(-3775 4750);
DISPLAY 0.936170 (-3775 4750);
PAINT GREEN (-3775 4750);
DISPLAY INVISIBLE (-3775 4750);
FORCEPROP 2 LAST PATH I130
J 0
(-3850 4925);
DISPLAY 0.787234 (-3850 4925);
PAINT MONO (-3850 4925);
DISPLAY INVISIBLE (-3850 4925);
FORCEADD TAP..6
(-3250 3850);
FORCEPROP 3 LASTPIN (-3200 3850) SIG_NAME M_J_BA<1>
J 0
(-3190 3860);
DISPLAY 0.659574 (-3190 3860);
PAINT MONO (-3190 3860);
DISPLAY INVISIBLE (-3190 3860);
FORCEPROP 1 LASTPIN (-3200 3850) BN 1
J 0
(-3250 3860);
DISPLAY 0.617021 (-3250 3860);
PAINT PINK (-3250 3860);
FORCEPROP 2 LAST CDS_LIB mstr_standard
J 0
(-3250 3850);
DISPLAY 0.787234 (-3250 3850);
PAINT MONO (-3250 3850);
DISPLAY INVISIBLE (-3250 3850);
FORCEPROP 1 LAST BODY_TYPE PLUMBING
J 0
(-3250 3800);
DISPLAY 1.234043 (-3250 3800);
PAINT GREEN (-3250 3800);
DISPLAY INVISIBLE (-3250 3800);
FORCEPROP 1 LAST HDL_TAP TRUE
J 0
(-2925 3725);
DISPLAY 1.234043 (-2925 3725);
PAINT GREEN (-2925 3725);
DISPLAY INVISIBLE (-2925 3725);
FORCEPROP 1 LAST PATH I131
J 0
(-3250 3850);
DISPLAY 0.936170 (-3250 3850);
PAINT GREEN (-3250 3850);
DISPLAY INVISIBLE (-3250 3850);
FORCEADD TAP..6
(-3250 3800);
FORCEPROP 3 LASTPIN (-3200 3800) SIG_NAME M_J_BA<0>
J 0
(-3190 3810);
DISPLAY 0.659574 (-3190 3810);
PAINT MONO (-3190 3810);
DISPLAY INVISIBLE (-3190 3810);
FORCEPROP 1 LASTPIN (-3200 3800) BN 0
J 0
(-3250 3810);
DISPLAY 0.617021 (-3250 3810);
PAINT PINK (-3250 3810);
FORCEPROP 2 LAST CDS_LIB mstr_standard
J 0
(-3250 3800);
DISPLAY 0.787234 (-3250 3800);
PAINT MONO (-3250 3800);
DISPLAY INVISIBLE (-3250 3800);
FORCEPROP 1 LAST BODY_TYPE PLUMBING
J 0
(-3250 3750);
DISPLAY 1.234043 (-3250 3750);
PAINT GREEN (-3250 3750);
DISPLAY INVISIBLE (-3250 3750);
FORCEPROP 1 LAST HDL_TAP TRUE
J 0
(-2925 3675);
DISPLAY 1.234043 (-2925 3675);
PAINT GREEN (-2925 3675);
DISPLAY INVISIBLE (-2925 3675);
FORCEPROP 1 LAST PATH I132
J 0
(-3250 3800);
DISPLAY 0.936170 (-3250 3800);
PAINT GREEN (-3250 3800);
DISPLAY INVISIBLE (-3250 3800);
FORCEADD TAP..6
(-3250 3700);
FORCEPROP 3 LASTPIN (-3200 3700) SIG_NAME M_J_BG<0>
J 0
(-3190 3710);
DISPLAY 0.659574 (-3190 3710);
PAINT MONO (-3190 3710);
DISPLAY INVISIBLE (-3190 3710);
FORCEPROP 1 LASTPIN (-3200 3700) BN 0
J 0
(-3250 3710);
DISPLAY 0.617021 (-3250 3710);
PAINT PINK (-3250 3710);
FORCEPROP 2 LAST CDS_LIB mstr_standard
J 0
(-3250 3700);
DISPLAY 0.787234 (-3250 3700);
PAINT MONO (-3250 3700);
DISPLAY INVISIBLE (-3250 3700);
FORCEPROP 1 LAST BODY_TYPE PLUMBING
J 0
(-3250 3650);
DISPLAY 1.234043 (-3250 3650);
PAINT GREEN (-3250 3650);
DISPLAY INVISIBLE (-3250 3650);
FORCEPROP 1 LAST HDL_TAP TRUE
J 0
(-2925 3575);
DISPLAY 1.234043 (-2925 3575);
PAINT GREEN (-2925 3575);
DISPLAY INVISIBLE (-2925 3575);
FORCEPROP 1 LAST PATH I133
J 0
(-3250 3700);
DISPLAY 0.936170 (-3250 3700);
PAINT GREEN (-3250 3700);
DISPLAY INVISIBLE (-3250 3700);
FORCEADD TAP..6
(-3250 3750);
FORCEPROP 3 LASTPIN (-3200 3750) SIG_NAME M_J_BG<1>
J 0
(-3190 3760);
DISPLAY 0.659574 (-3190 3760);
PAINT MONO (-3190 3760);
DISPLAY INVISIBLE (-3190 3760);
FORCEPROP 1 LASTPIN (-3200 3750) BN 1
J 0
(-3250 3760);
DISPLAY 0.617021 (-3250 3760);
PAINT PINK (-3250 3760);
FORCEPROP 2 LAST CDS_LIB mstr_standard
J 0
(-3250 3750);
DISPLAY 0.787234 (-3250 3750);
PAINT MONO (-3250 3750);
DISPLAY INVISIBLE (-3250 3750);
FORCEPROP 1 LAST BODY_TYPE PLUMBING
J 0
(-3250 3700);
DISPLAY 1.234043 (-3250 3700);
PAINT GREEN (-3250 3700);
DISPLAY INVISIBLE (-3250 3700);
FORCEPROP 1 LAST HDL_TAP TRUE
J 0
(-2925 3625);
DISPLAY 1.234043 (-2925 3625);
PAINT GREEN (-2925 3625);
DISPLAY INVISIBLE (-2925 3625);
FORCEPROP 1 LAST PATH I134
J 0
(-3250 3750);
DISPLAY 0.936170 (-3250 3750);
PAINT GREEN (-3250 3750);
DISPLAY INVISIBLE (-3250 3750);
FORCEADD OFFPAGE..1
(-3900 3400);
FORCEPROP 2 LAST $XR0 59 
J 0
(-4121 3400);
DISPLAY 0.638298 (-4121 3400);
PAINT MONO (-4121 3400);
FORCEPROP 2 LAST $XR1 81 
J 0
(-4211 3400);
DISPLAY 0.638298 (-4211 3400);
PAINT MONO (-4211 3400);
FORCEPROP 2 LAST CDS_LIB mstr_standard
J 0
(-3900 3400);
DISPLAY 0.787234 (-3900 3400);
PAINT MONO (-3900 3400);
DISPLAY INVISIBLE (-3900 3400);
FORCEPROP 1 LAST OFFPAGE TRUE
J 0
(-3575 3275);
DISPLAY 0.936170 (-3575 3275);
PAINT GREEN (-3575 3275);
DISPLAY INVISIBLE (-3575 3275);
FORCEPROP 1 LAST COMMENT_BODY TRUE
J 0
(-3775 3300);
DISPLAY 0.936170 (-3775 3300);
PAINT GREEN (-3775 3300);
DISPLAY INVISIBLE (-3775 3300);
FORCEPROP 2 LAST PATH I135
J 0
(-3850 3475);
DISPLAY 0.787234 (-3850 3475);
PAINT MONO (-3850 3475);
DISPLAY INVISIBLE (-3850 3475);
FORCEADD OFFPAGE..1
(-3900 3900);
FORCEPROP 2 LAST $XR0 59 
J 0
(-4121 3900);
DISPLAY 0.638298 (-4121 3900);
PAINT MONO (-4121 3900);
FORCEPROP 2 LAST $XR1 81 
J 0
(-4211 3900);
DISPLAY 0.638298 (-4211 3900);
PAINT MONO (-4211 3900);
FORCEPROP 2 LAST CDS_LIB mstr_standard
J 0
(-3900 3900);
DISPLAY 0.787234 (-3900 3900);
PAINT MONO (-3900 3900);
DISPLAY INVISIBLE (-3900 3900);
FORCEPROP 1 LAST OFFPAGE TRUE
J 0
(-3575 3775);
DISPLAY 0.936170 (-3575 3775);
PAINT GREEN (-3575 3775);
DISPLAY INVISIBLE (-3575 3775);
FORCEPROP 1 LAST COMMENT_BODY TRUE
J 0
(-3775 3800);
DISPLAY 0.936170 (-3775 3800);
PAINT GREEN (-3775 3800);
DISPLAY INVISIBLE (-3775 3800);
FORCEPROP 2 LAST PATH I136
J 0
(-3850 3975);
DISPLAY 0.787234 (-3850 3975);
PAINT MONO (-3850 3975);
DISPLAY INVISIBLE (-3850 3975);
FORCEADD OFFPAGE..1
(-3900 3800);
FORCEPROP 2 LAST $XR0 59 
J 0
(-4121 3800);
DISPLAY 0.638298 (-4121 3800);
PAINT MONO (-4121 3800);
FORCEPROP 2 LAST $XR1 81 
J 0
(-4211 3800);
DISPLAY 0.638298 (-4211 3800);
PAINT MONO (-4211 3800);
FORCEPROP 2 LAST CDS_LIB mstr_standard
J 0
(-3900 3800);
DISPLAY 0.787234 (-3900 3800);
PAINT MONO (-3900 3800);
DISPLAY INVISIBLE (-3900 3800);
FORCEPROP 1 LAST OFFPAGE TRUE
J 0
(-3575 3675);
DISPLAY 0.936170 (-3575 3675);
PAINT GREEN (-3575 3675);
DISPLAY INVISIBLE (-3575 3675);
FORCEPROP 1 LAST COMMENT_BODY TRUE
J 0
(-3775 3700);
DISPLAY 0.936170 (-3775 3700);
PAINT GREEN (-3775 3700);
DISPLAY INVISIBLE (-3775 3700);
FORCEPROP 2 LAST PATH I137
J 0
(-3850 3875);
DISPLAY 0.787234 (-3850 3875);
PAINT MONO (-3850 3875);
DISPLAY INVISIBLE (-3850 3875);
FORCEADD TAP..6
(-3300 2700);
FORCEPROP 3 LASTPIN (-3250 2700) SIG_NAME M_J_ECC<6>
J 0
(-3240 2710);
DISPLAY 0.659574 (-3240 2710);
PAINT MONO (-3240 2710);
DISPLAY INVISIBLE (-3240 2710);
FORCEPROP 1 LASTPIN (-3250 2700) BN 6
J 0
(-3300 2710);
DISPLAY 0.617021 (-3300 2710);
PAINT PINK (-3300 2710);
FORCEPROP 2 LAST CDS_LIB mstr_standard
J 0
(-3300 2700);
DISPLAY 0.787234 (-3300 2700);
PAINT MONO (-3300 2700);
DISPLAY INVISIBLE (-3300 2700);
FORCEPROP 1 LAST BODY_TYPE PLUMBING
J 0
(-3300 2650);
DISPLAY 1.234043 (-3300 2650);
PAINT GREEN (-3300 2650);
DISPLAY INVISIBLE (-3300 2650);
FORCEPROP 1 LAST HDL_TAP TRUE
J 0
(-2975 2575);
DISPLAY 1.234043 (-2975 2575);
PAINT GREEN (-2975 2575);
DISPLAY INVISIBLE (-2975 2575);
FORCEPROP 1 LAST PATH I138
J 0
(-3300 2700);
DISPLAY 0.936170 (-3300 2700);
PAINT GREEN (-3300 2700);
DISPLAY INVISIBLE (-3300 2700);
FORCEADD TAP..6
(-3300 2750);
FORCEPROP 3 LASTPIN (-3250 2750) SIG_NAME M_J_ECC<7>
J 0
(-3240 2760);
DISPLAY 0.659574 (-3240 2760);
PAINT MONO (-3240 2760);
DISPLAY INVISIBLE (-3240 2760);
FORCEPROP 1 LASTPIN (-3250 2750) BN 7
J 0
(-3300 2760);
DISPLAY 0.617021 (-3300 2760);
PAINT PINK (-3300 2760);
FORCEPROP 2 LAST CDS_LIB mstr_standard
J 0
(-3300 2750);
DISPLAY 0.787234 (-3300 2750);
PAINT MONO (-3300 2750);
DISPLAY INVISIBLE (-3300 2750);
FORCEPROP 1 LAST BODY_TYPE PLUMBING
J 0
(-3300 2700);
DISPLAY 1.234043 (-3300 2700);
PAINT GREEN (-3300 2700);
DISPLAY INVISIBLE (-3300 2700);
FORCEPROP 1 LAST HDL_TAP TRUE
J 0
(-2975 2625);
DISPLAY 1.234043 (-2975 2625);
PAINT GREEN (-2975 2625);
DISPLAY INVISIBLE (-2975 2625);
FORCEPROP 1 LAST PATH I139
J 0
(-3300 2750);
DISPLAY 0.936170 (-3300 2750);
PAINT GREEN (-3300 2750);
DISPLAY INVISIBLE (-3300 2750);
FORCEADD PVDDQ_GHJ..1
(-1400 2575);
FORCEPROP 3 LASTPIN (-1400 2525) SIG_NAME PVDDQ_GHJ\g
J 0
(-1390 2535);
DISPLAY 0.659574 (-1390 2535);
PAINT MONO (-1390 2535);
DISPLAY INVISIBLE (-1390 2535);
FORCEPROP 1 LAST VOLTAGE 1.2V
J 0
(-1445 2532);
DISPLAY 0.340426 (-1445 2532);
PAINT SKYBLUE (-1445 2532);
DISPLAY INVISIBLE (-1445 2532);
FORCEPROP 2 LAST BOM_COST MEM
J 0
(-1400 2580);
PAINT ORANGE (-1400 2580);
DISPLAY INVISIBLE (-1400 2580);
FORCEPROP 2 LAST CDS_LIB mstr_symbols
J 0
(-1400 2575);
PAINT ORANGE (-1400 2575);
DISPLAY INVISIBLE (-1400 2575);
FORCEPROP 1 LAST BODY_TYPE PLUMBING
J 0
(-1445 2532);
DISPLAY 0.340426 (-1445 2532);
PAINT GREEN (-1445 2532);
DISPLAY INVISIBLE (-1445 2532);
FORCEPROP 1 LAST PATH I14
J 0
(-1350 2600);
DISPLAY 0.872340 (-1350 2600);
PAINT AQUA (-1350 2600);
DISPLAY INVISIBLE (-1350 2600);
FORCEPROP 2 LAST ROOM DDR4_CH_J
J 0
(-1400 2675);
DISPLAY 0.787234 (-1400 2675);
PAINT ORANGE (-1400 2675);
DISPLAY INVISIBLE (-1400 2675);
FORCEPROP 1 LAST HDL_POWER PVDDQ_GHJ
J 1
(-1400 2625);
DISPLAY 0.872340 (-1400 2625);
PAINT GREEN (-1400 2625);
DISPLAY INVISIBLE (-1400 2625);
FORCEADD TAP..6
(-3300 2650);
FORCEPROP 3 LASTPIN (-3250 2650) SIG_NAME M_J_ECC<5>
J 0
(-3240 2660);
DISPLAY 0.659574 (-3240 2660);
PAINT MONO (-3240 2660);
DISPLAY INVISIBLE (-3240 2660);
FORCEPROP 1 LASTPIN (-3250 2650) BN 5
J 0
(-3300 2660);
DISPLAY 0.617021 (-3300 2660);
PAINT PINK (-3300 2660);
FORCEPROP 2 LAST CDS_LIB mstr_standard
J 0
(-3300 2650);
DISPLAY 0.787234 (-3300 2650);
PAINT MONO (-3300 2650);
DISPLAY INVISIBLE (-3300 2650);
FORCEPROP 1 LAST BODY_TYPE PLUMBING
J 0
(-3300 2600);
DISPLAY 1.234043 (-3300 2600);
PAINT GREEN (-3300 2600);
DISPLAY INVISIBLE (-3300 2600);
FORCEPROP 1 LAST HDL_TAP TRUE
J 0
(-2975 2525);
DISPLAY 1.234043 (-2975 2525);
PAINT GREEN (-2975 2525);
DISPLAY INVISIBLE (-2975 2525);
FORCEPROP 1 LAST PATH I140
J 0
(-3300 2650);
DISPLAY 0.936170 (-3300 2650);
PAINT GREEN (-3300 2650);
DISPLAY INVISIBLE (-3300 2650);
FORCEADD TAP..6
(-3300 2600);
FORCEPROP 3 LASTPIN (-3250 2600) SIG_NAME M_J_ECC<4>
J 0
(-3240 2610);
DISPLAY 0.659574 (-3240 2610);
PAINT MONO (-3240 2610);
DISPLAY INVISIBLE (-3240 2610);
FORCEPROP 1 LASTPIN (-3250 2600) BN 4
J 0
(-3300 2610);
DISPLAY 0.617021 (-3300 2610);
PAINT PINK (-3300 2610);
FORCEPROP 2 LAST CDS_LIB mstr_standard
J 0
(-3300 2600);
DISPLAY 0.787234 (-3300 2600);
PAINT MONO (-3300 2600);
DISPLAY INVISIBLE (-3300 2600);
FORCEPROP 1 LAST BODY_TYPE PLUMBING
J 0
(-3300 2550);
DISPLAY 1.234043 (-3300 2550);
PAINT GREEN (-3300 2550);
DISPLAY INVISIBLE (-3300 2550);
FORCEPROP 1 LAST HDL_TAP TRUE
J 0
(-2975 2475);
DISPLAY 1.234043 (-2975 2475);
PAINT GREEN (-2975 2475);
DISPLAY INVISIBLE (-2975 2475);
FORCEPROP 1 LAST PATH I141
J 0
(-3300 2600);
DISPLAY 0.936170 (-3300 2600);
PAINT GREEN (-3300 2600);
DISPLAY INVISIBLE (-3300 2600);
FORCEADD TAP..6
(-3300 2550);
FORCEPROP 3 LASTPIN (-3250 2550) SIG_NAME M_J_ECC<3>
J 0
(-3240 2560);
DISPLAY 0.659574 (-3240 2560);
PAINT MONO (-3240 2560);
DISPLAY INVISIBLE (-3240 2560);
FORCEPROP 1 LASTPIN (-3250 2550) BN 3
J 0
(-3300 2560);
DISPLAY 0.617021 (-3300 2560);
PAINT PINK (-3300 2560);
FORCEPROP 2 LAST CDS_LIB mstr_standard
J 0
(-3300 2550);
DISPLAY 0.787234 (-3300 2550);
PAINT MONO (-3300 2550);
DISPLAY INVISIBLE (-3300 2550);
FORCEPROP 1 LAST BODY_TYPE PLUMBING
J 0
(-3300 2500);
DISPLAY 1.234043 (-3300 2500);
PAINT GREEN (-3300 2500);
DISPLAY INVISIBLE (-3300 2500);
FORCEPROP 1 LAST HDL_TAP TRUE
J 0
(-2975 2425);
DISPLAY 1.234043 (-2975 2425);
PAINT GREEN (-2975 2425);
DISPLAY INVISIBLE (-2975 2425);
FORCEPROP 1 LAST PATH I142
J 0
(-3300 2550);
DISPLAY 0.936170 (-3300 2550);
PAINT GREEN (-3300 2550);
DISPLAY INVISIBLE (-3300 2550);
FORCEADD TAP..6
(-3300 2450);
FORCEPROP 3 LASTPIN (-3250 2450) SIG_NAME M_J_ECC<1>
J 0
(-3240 2460);
DISPLAY 0.659574 (-3240 2460);
PAINT MONO (-3240 2460);
DISPLAY INVISIBLE (-3240 2460);
FORCEPROP 1 LASTPIN (-3250 2450) BN 1
J 0
(-3300 2460);
DISPLAY 0.617021 (-3300 2460);
PAINT PINK (-3300 2460);
FORCEPROP 2 LAST CDS_LIB mstr_standard
J 0
(-3300 2450);
DISPLAY 0.787234 (-3300 2450);
PAINT MONO (-3300 2450);
DISPLAY INVISIBLE (-3300 2450);
FORCEPROP 1 LAST BODY_TYPE PLUMBING
J 0
(-3300 2400);
DISPLAY 1.234043 (-3300 2400);
PAINT GREEN (-3300 2400);
DISPLAY INVISIBLE (-3300 2400);
FORCEPROP 1 LAST HDL_TAP TRUE
J 0
(-2975 2325);
DISPLAY 1.234043 (-2975 2325);
PAINT GREEN (-2975 2325);
DISPLAY INVISIBLE (-2975 2325);
FORCEPROP 1 LAST PATH I143
J 0
(-3300 2450);
DISPLAY 0.936170 (-3300 2450);
PAINT GREEN (-3300 2450);
DISPLAY INVISIBLE (-3300 2450);
FORCEADD TAP..6
(-3300 2500);
FORCEPROP 3 LASTPIN (-3250 2500) SIG_NAME M_J_ECC<2>
J 0
(-3240 2510);
DISPLAY 0.659574 (-3240 2510);
PAINT MONO (-3240 2510);
DISPLAY INVISIBLE (-3240 2510);
FORCEPROP 1 LASTPIN (-3250 2500) BN 2
J 0
(-3300 2510);
DISPLAY 0.617021 (-3300 2510);
PAINT PINK (-3300 2510);
FORCEPROP 2 LAST CDS_LIB mstr_standard
J 0
(-3300 2500);
DISPLAY 0.787234 (-3300 2500);
PAINT MONO (-3300 2500);
DISPLAY INVISIBLE (-3300 2500);
FORCEPROP 1 LAST BODY_TYPE PLUMBING
J 0
(-3300 2450);
DISPLAY 1.234043 (-3300 2450);
PAINT GREEN (-3300 2450);
DISPLAY INVISIBLE (-3300 2450);
FORCEPROP 1 LAST HDL_TAP TRUE
J 0
(-2975 2375);
DISPLAY 1.234043 (-2975 2375);
PAINT GREEN (-2975 2375);
DISPLAY INVISIBLE (-2975 2375);
FORCEPROP 1 LAST PATH I144
J 0
(-3300 2500);
DISPLAY 0.936170 (-3300 2500);
PAINT GREEN (-3300 2500);
DISPLAY INVISIBLE (-3300 2500);
FORCEADD TAP..6
(-3300 2400);
FORCEPROP 3 LASTPIN (-3250 2400) SIG_NAME M_J_ECC<0>
J 0
(-3240 2410);
DISPLAY 0.659574 (-3240 2410);
PAINT MONO (-3240 2410);
DISPLAY INVISIBLE (-3240 2410);
FORCEPROP 1 LASTPIN (-3250 2400) BN 0
J 0
(-3300 2410);
DISPLAY 0.617021 (-3300 2410);
PAINT PINK (-3300 2410);
FORCEPROP 2 LAST CDS_LIB mstr_standard
J 0
(-3300 2400);
DISPLAY 0.787234 (-3300 2400);
PAINT MONO (-3300 2400);
DISPLAY INVISIBLE (-3300 2400);
FORCEPROP 1 LAST BODY_TYPE PLUMBING
J 0
(-3300 2350);
DISPLAY 1.234043 (-3300 2350);
PAINT GREEN (-3300 2350);
DISPLAY INVISIBLE (-3300 2350);
FORCEPROP 1 LAST HDL_TAP TRUE
J 0
(-2975 2275);
DISPLAY 1.234043 (-2975 2275);
PAINT GREEN (-2975 2275);
DISPLAY INVISIBLE (-2975 2275);
FORCEPROP 1 LAST PATH I145
J 0
(-3300 2400);
DISPLAY 0.936170 (-3300 2400);
PAINT GREEN (-3300 2400);
DISPLAY INVISIBLE (-3300 2400);
FORCEADD OFFPAGE..1
(-3900 2750);
FORCEPROP 2 LAST $XR0 59 
J 0
(-4181 2750);
DISPLAY 0.638298 (-4181 2750);
PAINT MONO (-4181 2750);
FORCEPROP 2 LAST $XR1 81 
J 0
(-4271 2750);
DISPLAY 0.638298 (-4271 2750);
PAINT MONO (-4271 2750);
FORCEPROP 2 LAST CDS_LIB mstr_standard
J 0
(-3900 2750);
DISPLAY 0.787234 (-3900 2750);
PAINT MONO (-3900 2750);
DISPLAY INVISIBLE (-3900 2750);
FORCEPROP 1 LAST OFFPAGE TRUE
J 0
(-3575 2625);
DISPLAY 0.936170 (-3575 2625);
PAINT GREEN (-3575 2625);
DISPLAY INVISIBLE (-3575 2625);
FORCEPROP 1 LAST COMMENT_BODY TRUE
J 0
(-3775 2650);
DISPLAY 0.936170 (-3775 2650);
PAINT GREEN (-3775 2650);
DISPLAY INVISIBLE (-3775 2650);
FORCEPROP 2 LAST PATH I146
J 0
(-3850 2825);
DISPLAY 0.787234 (-3850 2825);
PAINT MONO (-3850 2825);
DISPLAY INVISIBLE (-3850 2825);
FORCEADD OFFPAGE..1
(-4100 2100);
FORCEPROP 2 LAST $XR0 59 
J 0
(-4381 2100);
DISPLAY 0.638298 (-4381 2100);
PAINT MONO (-4381 2100);
FORCEPROP 2 LAST $XR1 81 
J 0
(-4471 2100);
DISPLAY 0.638298 (-4471 2100);
PAINT MONO (-4471 2100);
FORCEPROP 2 LAST CDS_LIB mstr_standard
J 0
(-4100 2100);
DISPLAY 0.787234 (-4100 2100);
PAINT MONO (-4100 2100);
DISPLAY INVISIBLE (-4100 2100);
FORCEPROP 1 LAST OFFPAGE TRUE
J 0
(-3775 1975);
DISPLAY 0.936170 (-3775 1975);
PAINT GREEN (-3775 1975);
DISPLAY INVISIBLE (-3775 1975);
FORCEPROP 1 LAST COMMENT_BODY TRUE
J 0
(-3975 2000);
DISPLAY 0.936170 (-3975 2000);
PAINT GREEN (-3975 2000);
DISPLAY INVISIBLE (-3975 2000);
FORCEPROP 2 LAST PATH I147
J 0
(-4050 2175);
DISPLAY 0.787234 (-4050 2175);
PAINT MONO (-4050 2175);
DISPLAY INVISIBLE (-4050 2175);
FORCEADD OFFPAGE..5
(-4125 2150);
FORCEPROP 2 LAST $XR0 81 
J 0
(-4379 2150);
DISPLAY 0.638298 (-4379 2150);
PAINT MONO (-4379 2150);
FORCEPROP 2 LAST $XR1 59 
J 0
(-4469 2150);
DISPLAY 0.638298 (-4469 2150);
PAINT MONO (-4469 2150);
FORCEPROP 2 LAST CDS_LIB mstr_standard
J 0
(-4125 2150);
DISPLAY 0.787234 (-4125 2150);
PAINT MONO (-4125 2150);
DISPLAY INVISIBLE (-4125 2150);
FORCEPROP 1 LAST OFFPAGE TRUE
J 0
(-3800 2025);
DISPLAY 1.404255 (-3800 2025);
PAINT GREEN (-3800 2025);
DISPLAY INVISIBLE (-3800 2025);
FORCEPROP 1 LAST COMMENT_BODY TRUE
J 0
(-4025 2075);
DISPLAY 1.404255 (-4025 2075);
PAINT GREEN (-4025 2075);
DISPLAY INVISIBLE (-4025 2075);
FORCEPROP 2 LAST PATH I148
J 0
(-4075 2225);
DISPLAY 0.787234 (-4075 2225);
PAINT MONO (-4075 2225);
DISPLAY INVISIBLE (-4075 2225);
FORCEADD OFFPAGE..1
(-3900 2700);
FORCEPROP 2 LAST $XR0 55 
J 0
(-4121 2700);
DISPLAY 0.638298 (-4121 2700);
PAINT MONO (-4121 2700);
FORCEPROP 2 LAST $XR1 77 
J 0
(-4211 2700);
DISPLAY 0.638298 (-4211 2700);
PAINT MONO (-4211 2700);
FORCEPROP 2 LAST $XR2 78 
J 0
(-4301 2700);
DISPLAY 0.638298 (-4301 2700);
PAINT MONO (-4301 2700);
FORCEPROP 2 LAST $XR3 79 
J 0
(-4391 2700);
DISPLAY 0.638298 (-4391 2700);
PAINT MONO (-4391 2700);
FORCEPROP 2 LAST $XR4 80 
J 0
(-4481 2700);
DISPLAY 0.638298 (-4481 2700);
PAINT MONO (-4481 2700);
FORCEPROP 2 LAST $XR5 81 
J 0
(-4571 2700);
DISPLAY 0.638298 (-4571 2700);
PAINT MONO (-4571 2700);
FORCEPROP 2 LAST CDS_LIB mstr_standard
J 0
(-3900 2700);
DISPLAY 0.787234 (-3900 2700);
PAINT MONO (-3900 2700);
DISPLAY INVISIBLE (-3900 2700);
FORCEPROP 1 LAST OFFPAGE TRUE
J 0
(-3575 2575);
DISPLAY 0.936170 (-3575 2575);
PAINT GREEN (-3575 2575);
DISPLAY INVISIBLE (-3575 2575);
FORCEPROP 1 LAST COMMENT_BODY TRUE
J 0
(-3775 2600);
DISPLAY 0.936170 (-3775 2600);
PAINT GREEN (-3775 2600);
DISPLAY INVISIBLE (-3775 2600);
FORCEPROP 2 LAST PATH I149
J 0
(-3850 2775);
DISPLAY 0.787234 (-3850 2775);
PAINT MONO (-3850 2775);
DISPLAY INVISIBLE (-3850 2775);
FORCEADD OFFPAGE..6
(-3900 2800);
FORCEPROP 2 LAST $XR0 59 
J 0
(-4179 2800);
DISPLAY 0.638298 (-4179 2800);
PAINT MONO (-4179 2800);
FORCEPROP 2 LAST $XR1 81 
J 0
(-4269 2800);
DISPLAY 0.638298 (-4269 2800);
PAINT MONO (-4269 2800);
FORCEPROP 2 LAST CDS_LIB mstr_standard
J 0
(-3900 2800);
DISPLAY 0.787234 (-3900 2800);
PAINT MONO (-3900 2800);
DISPLAY INVISIBLE (-3900 2800);
FORCEPROP 1 LAST OFFPAGE TRUE
J 0
(-3575 2675);
DISPLAY 0.936170 (-3575 2675);
PAINT GREEN (-3575 2675);
DISPLAY INVISIBLE (-3575 2675);
FORCEPROP 1 LAST COMMENT_BODY TRUE
J 0
(-3800 2725);
DISPLAY 0.936170 (-3800 2725);
PAINT GREEN (-3800 2725);
DISPLAY INVISIBLE (-3800 2725);
FORCEPROP 2 LAST PATH I150
J 0
(-3850 2875);
DISPLAY 0.787234 (-3850 2875);
PAINT MONO (-3850 2875);
DISPLAY INVISIBLE (-3850 2875);
FORCEADD TAP..6
(-3250 3600);
FORCEPROP 3 LASTPIN (-3200 3600) SIG_NAME M_J_CLK_DP<3>
J 0
(-3190 3610);
DISPLAY 0.659574 (-3190 3610);
PAINT MONO (-3190 3610);
DISPLAY INVISIBLE (-3190 3610);
FORCEPROP 1 LASTPIN (-3200 3600) BN 3
J 0
(-3250 3610);
DISPLAY 0.617021 (-3250 3610);
PAINT PINK (-3250 3610);
FORCEPROP 2 LAST CDS_LIB mstr_standard
J 0
(-3250 3600);
DISPLAY 0.787234 (-3250 3600);
PAINT MONO (-3250 3600);
DISPLAY INVISIBLE (-3250 3600);
FORCEPROP 1 LAST BODY_TYPE PLUMBING
J 0
(-3250 3550);
DISPLAY 1.234043 (-3250 3550);
PAINT GREEN (-3250 3550);
DISPLAY INVISIBLE (-3250 3550);
FORCEPROP 1 LAST HDL_TAP TRUE
J 0
(-2925 3475);
DISPLAY 1.234043 (-2925 3475);
PAINT GREEN (-2925 3475);
DISPLAY INVISIBLE (-2925 3475);
FORCEPROP 1 LAST PATH I152
J 0
(-3250 3600);
DISPLAY 0.936170 (-3250 3600);
PAINT GREEN (-3250 3600);
DISPLAY INVISIBLE (-3250 3600);
FORCEADD TAP..6
(-3250 3500);
FORCEPROP 3 LASTPIN (-3200 3500) SIG_NAME M_J_CLK_DP<2>
J 0
(-3190 3510);
DISPLAY 0.659574 (-3190 3510);
PAINT MONO (-3190 3510);
DISPLAY INVISIBLE (-3190 3510);
FORCEPROP 1 LASTPIN (-3200 3500) BN 2
J 0
(-3250 3510);
DISPLAY 0.617021 (-3250 3510);
PAINT PINK (-3250 3510);
FORCEPROP 2 LAST CDS_LIB mstr_standard
J 0
(-3250 3500);
DISPLAY 0.787234 (-3250 3500);
PAINT MONO (-3250 3500);
DISPLAY INVISIBLE (-3250 3500);
FORCEPROP 1 LAST BODY_TYPE PLUMBING
J 0
(-3250 3450);
DISPLAY 1.234043 (-3250 3450);
PAINT GREEN (-3250 3450);
DISPLAY INVISIBLE (-3250 3450);
FORCEPROP 1 LAST HDL_TAP TRUE
J 0
(-2925 3375);
DISPLAY 1.234043 (-2925 3375);
PAINT GREEN (-2925 3375);
DISPLAY INVISIBLE (-2925 3375);
FORCEPROP 1 LAST PATH I153
J 0
(-3250 3500);
DISPLAY 0.936170 (-3250 3500);
PAINT GREEN (-3250 3500);
DISPLAY INVISIBLE (-3250 3500);
FORCEADD TAP..6
(-3450 3550);
FORCEPROP 3 LASTPIN (-3400 3550) SIG_NAME M_J_CLK_DN<3>
J 0
(-3390 3560);
DISPLAY 0.659574 (-3390 3560);
PAINT MONO (-3390 3560);
DISPLAY INVISIBLE (-3390 3560);
FORCEPROP 1 LASTPIN (-3400 3550) BN 3
J 0
(-3450 3560);
DISPLAY 0.617021 (-3450 3560);
PAINT PINK (-3450 3560);
FORCEPROP 2 LAST CDS_LIB mstr_standard
J 0
(-3450 3550);
DISPLAY 0.787234 (-3450 3550);
PAINT MONO (-3450 3550);
DISPLAY INVISIBLE (-3450 3550);
FORCEPROP 1 LAST BODY_TYPE PLUMBING
J 0
(-3450 3500);
DISPLAY 1.234043 (-3450 3500);
PAINT GREEN (-3450 3500);
DISPLAY INVISIBLE (-3450 3500);
FORCEPROP 1 LAST HDL_TAP TRUE
J 0
(-3125 3425);
DISPLAY 1.234043 (-3125 3425);
PAINT GREEN (-3125 3425);
DISPLAY INVISIBLE (-3125 3425);
FORCEPROP 1 LAST PATH I154
J 0
(-3450 3550);
DISPLAY 0.936170 (-3450 3550);
PAINT GREEN (-3450 3550);
DISPLAY INVISIBLE (-3450 3550);
FORCEADD TAP..6
(-3450 3450);
FORCEPROP 3 LASTPIN (-3400 3450) SIG_NAME M_J_CLK_DN<2>
J 0
(-3390 3460);
DISPLAY 0.659574 (-3390 3460);
PAINT MONO (-3390 3460);
DISPLAY INVISIBLE (-3390 3460);
FORCEPROP 1 LASTPIN (-3400 3450) BN 2
J 0
(-3450 3460);
DISPLAY 0.617021 (-3450 3460);
PAINT PINK (-3450 3460);
FORCEPROP 2 LAST CDS_LIB mstr_standard
J 0
(-3450 3450);
DISPLAY 0.787234 (-3450 3450);
PAINT MONO (-3450 3450);
DISPLAY INVISIBLE (-3450 3450);
FORCEPROP 1 LAST BODY_TYPE PLUMBING
J 0
(-3450 3400);
DISPLAY 1.234043 (-3450 3400);
PAINT GREEN (-3450 3400);
DISPLAY INVISIBLE (-3450 3400);
FORCEPROP 1 LAST HDL_TAP TRUE
J 0
(-3125 3325);
DISPLAY 1.234043 (-3125 3325);
PAINT GREEN (-3125 3325);
DISPLAY INVISIBLE (-3125 3325);
FORCEPROP 1 LAST PATH I155
J 0
(-3450 3450);
DISPLAY 0.936170 (-3450 3450);
PAINT GREEN (-3450 3450);
DISPLAY INVISIBLE (-3450 3450);
FORCEADD OFFPAGE..1
(-3900 3650);
FORCEPROP 2 LAST $XR0 59 
J 0
(-4121 3650);
DISPLAY 0.638298 (-4121 3650);
PAINT MONO (-4121 3650);
FORCEPROP 2 LAST $XR1 81 
J 0
(-4211 3650);
DISPLAY 0.638298 (-4211 3650);
PAINT MONO (-4211 3650);
FORCEPROP 2 LAST CDS_LIB mstr_standard
J 0
(-3900 3650);
DISPLAY 0.787234 (-3900 3650);
PAINT MONO (-3900 3650);
DISPLAY INVISIBLE (-3900 3650);
FORCEPROP 1 LAST OFFPAGE TRUE
J 0
(-3575 3525);
DISPLAY 0.936170 (-3575 3525);
PAINT GREEN (-3575 3525);
DISPLAY INVISIBLE (-3575 3525);
FORCEPROP 1 LAST COMMENT_BODY TRUE
J 0
(-3775 3550);
DISPLAY 0.936170 (-3775 3550);
PAINT GREEN (-3775 3550);
DISPLAY INVISIBLE (-3775 3550);
FORCEPROP 2 LAST PATH I156
J 0
(-3850 3725);
DISPLAY 0.787234 (-3850 3725);
PAINT MONO (-3850 3725);
DISPLAY INVISIBLE (-3850 3725);
FORCEADD OFFPAGE..1
(-3900 3600);
FORCEPROP 2 LAST $XR0 59 
J 0
(-4121 3600);
DISPLAY 0.638298 (-4121 3600);
PAINT MONO (-4121 3600);
FORCEPROP 2 LAST $XR1 81 
J 0
(-4211 3600);
DISPLAY 0.638298 (-4211 3600);
PAINT MONO (-4211 3600);
FORCEPROP 2 LAST CDS_LIB mstr_standard
J 0
(-3900 3600);
DISPLAY 0.787234 (-3900 3600);
PAINT MONO (-3900 3600);
DISPLAY INVISIBLE (-3900 3600);
FORCEPROP 1 LAST OFFPAGE TRUE
J 0
(-3575 3475);
DISPLAY 0.936170 (-3575 3475);
PAINT GREEN (-3575 3475);
DISPLAY INVISIBLE (-3575 3475);
FORCEPROP 1 LAST COMMENT_BODY TRUE
J 0
(-3775 3500);
DISPLAY 0.936170 (-3775 3500);
PAINT GREEN (-3775 3500);
DISPLAY INVISIBLE (-3775 3500);
FORCEPROP 2 LAST PATH I157
J 0
(-3850 3675);
DISPLAY 0.787234 (-3850 3675);
PAINT MONO (-3850 3675);
DISPLAY INVISIBLE (-3850 3675);
FORCEADD TAP..6
(-3300 3300);
FORCEPROP 3 LASTPIN (-3250 3300) SIG_NAME M_J_CS_N<7>
J 0
(-3240 3310);
DISPLAY 0.659574 (-3240 3310);
PAINT MONO (-3240 3310);
DISPLAY INVISIBLE (-3240 3310);
FORCEPROP 1 LASTPIN (-3250 3300) BN 7
J 0
(-3300 3310);
DISPLAY 0.617021 (-3300 3310);
PAINT PINK (-3300 3310);
FORCEPROP 2 LAST CDS_LIB mstr_standard
J 0
(-3300 3300);
DISPLAY 0.787234 (-3300 3300);
PAINT MONO (-3300 3300);
DISPLAY INVISIBLE (-3300 3300);
FORCEPROP 1 LAST BODY_TYPE PLUMBING
J 0
(-3300 3250);
DISPLAY 1.234043 (-3300 3250);
PAINT GREEN (-3300 3250);
DISPLAY INVISIBLE (-3300 3250);
FORCEPROP 1 LAST HDL_TAP TRUE
J 0
(-2975 3175);
DISPLAY 1.234043 (-2975 3175);
PAINT GREEN (-2975 3175);
DISPLAY INVISIBLE (-2975 3175);
FORCEPROP 1 LAST PATH I158
J 0
(-3300 3300);
DISPLAY 0.936170 (-3300 3300);
PAINT GREEN (-3300 3300);
DISPLAY INVISIBLE (-3300 3300);
FORCEADD TAP..6
(-3300 3250);
FORCEPROP 3 LASTPIN (-3250 3250) SIG_NAME M_J_CS_N<6>
J 0
(-3240 3260);
DISPLAY 0.659574 (-3240 3260);
PAINT MONO (-3240 3260);
DISPLAY INVISIBLE (-3240 3260);
FORCEPROP 1 LASTPIN (-3250 3250) BN 6
J 0
(-3300 3260);
DISPLAY 0.617021 (-3300 3260);
PAINT PINK (-3300 3260);
FORCEPROP 2 LAST CDS_LIB mstr_standard
J 0
(-3300 3250);
DISPLAY 0.787234 (-3300 3250);
PAINT MONO (-3300 3250);
DISPLAY INVISIBLE (-3300 3250);
FORCEPROP 1 LAST BODY_TYPE PLUMBING
J 0
(-3300 3200);
DISPLAY 1.234043 (-3300 3200);
PAINT GREEN (-3300 3200);
DISPLAY INVISIBLE (-3300 3200);
FORCEPROP 1 LAST HDL_TAP TRUE
J 0
(-2975 3125);
DISPLAY 1.234043 (-2975 3125);
PAINT GREEN (-2975 3125);
DISPLAY INVISIBLE (-2975 3125);
FORCEPROP 1 LAST PATH I159
J 0
(-3300 3250);
DISPLAY 0.936170 (-3300 3250);
PAINT GREEN (-3300 3250);
DISPLAY INVISIBLE (-3300 3250);
FORCEADD PVTT_GHJ..1
(-1200 2750);
FORCEPROP 3 LASTPIN (-1200 2700) SIG_NAME PVTT_GHJ\g
J 0
(-1190 2710);
DISPLAY 0.659574 (-1190 2710);
PAINT MONO (-1190 2710);
DISPLAY INVISIBLE (-1190 2710);
FORCEPROP 1 LAST VOLTAGE 0.6V
J 0
(-1245 2707);
DISPLAY 0.340426 (-1245 2707);
PAINT SKYBLUE (-1245 2707);
DISPLAY INVISIBLE (-1245 2707);
FORCEPROP 2 LAST BOM_COST MEM
J 0
(-1200 2755);
PAINT ORANGE (-1200 2755);
DISPLAY INVISIBLE (-1200 2755);
FORCEPROP 2 LAST CDS_LIB mstr_symbols
J 0
(-1200 2750);
PAINT ORANGE (-1200 2750);
DISPLAY INVISIBLE (-1200 2750);
FORCEPROP 1 LAST BODY_TYPE PLUMBING
J 0
(-1245 2707);
DISPLAY 0.340426 (-1245 2707);
PAINT GREEN (-1245 2707);
DISPLAY INVISIBLE (-1245 2707);
FORCEPROP 1 LAST PATH I16
J 0
(-1150 2775);
DISPLAY 0.872340 (-1150 2775);
PAINT AQUA (-1150 2775);
DISPLAY INVISIBLE (-1150 2775);
FORCEPROP 2 LAST ROOM DDR4_CH_J
J 0
(-1200 2850);
DISPLAY 0.787234 (-1200 2850);
PAINT ORANGE (-1200 2850);
DISPLAY INVISIBLE (-1200 2850);
FORCEPROP 1 LAST HDL_POWER PVTT_GHJ
J 1
(-1200 2800);
DISPLAY 0.872340 (-1200 2800);
PAINT GREEN (-1200 2800);
DISPLAY INVISIBLE (-1200 2800);
FORCEADD TAP..6
(-3300 3200);
FORCEPROP 3 LASTPIN (-3250 3200) SIG_NAME M_J_CS_N<5>
J 0
(-3240 3210);
DISPLAY 0.659574 (-3240 3210);
PAINT MONO (-3240 3210);
DISPLAY INVISIBLE (-3240 3210);
FORCEPROP 1 LASTPIN (-3250 3200) BN 5
J 0
(-3300 3210);
DISPLAY 0.617021 (-3300 3210);
PAINT PINK (-3300 3210);
FORCEPROP 2 LAST CDS_LIB mstr_standard
J 0
(-3300 3200);
DISPLAY 0.787234 (-3300 3200);
PAINT MONO (-3300 3200);
DISPLAY INVISIBLE (-3300 3200);
FORCEPROP 1 LAST BODY_TYPE PLUMBING
J 0
(-3300 3150);
DISPLAY 1.234043 (-3300 3150);
PAINT GREEN (-3300 3150);
DISPLAY INVISIBLE (-3300 3150);
FORCEPROP 1 LAST HDL_TAP TRUE
J 0
(-2975 3075);
DISPLAY 1.234043 (-2975 3075);
PAINT GREEN (-2975 3075);
DISPLAY INVISIBLE (-2975 3075);
FORCEPROP 1 LAST PATH I160
J 0
(-3300 3200);
DISPLAY 0.936170 (-3300 3200);
PAINT GREEN (-3300 3200);
DISPLAY INVISIBLE (-3300 3200);
FORCEADD TAP..6
(-3300 3150);
FORCEPROP 3 LASTPIN (-3250 3150) SIG_NAME M_J_CS_N<4>
J 0
(-3240 3160);
DISPLAY 0.659574 (-3240 3160);
PAINT MONO (-3240 3160);
DISPLAY INVISIBLE (-3240 3160);
FORCEPROP 1 LASTPIN (-3250 3150) BN 4
J 0
(-3300 3160);
DISPLAY 0.617021 (-3300 3160);
PAINT PINK (-3300 3160);
FORCEPROP 2 LAST CDS_LIB mstr_standard
J 0
(-3300 3150);
DISPLAY 0.787234 (-3300 3150);
PAINT MONO (-3300 3150);
DISPLAY INVISIBLE (-3300 3150);
FORCEPROP 1 LAST BODY_TYPE PLUMBING
J 0
(-3300 3100);
DISPLAY 1.234043 (-3300 3100);
PAINT GREEN (-3300 3100);
DISPLAY INVISIBLE (-3300 3100);
FORCEPROP 1 LAST HDL_TAP TRUE
J 0
(-2975 3025);
DISPLAY 1.234043 (-2975 3025);
PAINT GREEN (-2975 3025);
DISPLAY INVISIBLE (-2975 3025);
FORCEPROP 1 LAST PATH I161
J 0
(-3300 3150);
DISPLAY 0.936170 (-3300 3150);
PAINT GREEN (-3300 3150);
DISPLAY INVISIBLE (-3300 3150);
FORCEADD TAP..6
(-3300 3050);
FORCEPROP 3 LASTPIN (-3250 3050) SIG_NAME M_J_CKE<3>
J 0
(-3240 3060);
DISPLAY 0.659574 (-3240 3060);
PAINT MONO (-3240 3060);
DISPLAY INVISIBLE (-3240 3060);
FORCEPROP 1 LASTPIN (-3250 3050) BN 3
J 0
(-3300 3060);
DISPLAY 0.617021 (-3300 3060);
PAINT PINK (-3300 3060);
FORCEPROP 2 LAST CDS_LIB mstr_standard
J 0
(-3300 3050);
DISPLAY 0.787234 (-3300 3050);
PAINT MONO (-3300 3050);
DISPLAY INVISIBLE (-3300 3050);
FORCEPROP 1 LAST BODY_TYPE PLUMBING
J 0
(-3300 3000);
DISPLAY 1.234043 (-3300 3000);
PAINT GREEN (-3300 3000);
DISPLAY INVISIBLE (-3300 3000);
FORCEPROP 1 LAST HDL_TAP TRUE
J 0
(-2975 2925);
DISPLAY 1.234043 (-2975 2925);
PAINT GREEN (-2975 2925);
DISPLAY INVISIBLE (-2975 2925);
FORCEPROP 1 LAST PATH I162
J 0
(-3300 3050);
DISPLAY 0.936170 (-3300 3050);
PAINT GREEN (-3300 3050);
DISPLAY INVISIBLE (-3300 3050);
FORCEADD OFFPAGE..1
(-3900 3350);
FORCEPROP 2 LAST $XR0 59 
J 0
(-4121 3350);
DISPLAY 0.638298 (-4121 3350);
PAINT MONO (-4121 3350);
FORCEPROP 2 LAST $XR1 81 
J 0
(-4211 3350);
DISPLAY 0.638298 (-4211 3350);
PAINT MONO (-4211 3350);
FORCEPROP 2 LAST CDS_LIB mstr_standard
J 0
(-3900 3350);
DISPLAY 0.787234 (-3900 3350);
PAINT MONO (-3900 3350);
DISPLAY INVISIBLE (-3900 3350);
FORCEPROP 1 LAST OFFPAGE TRUE
J 0
(-3575 3225);
DISPLAY 0.936170 (-3575 3225);
PAINT GREEN (-3575 3225);
DISPLAY INVISIBLE (-3575 3225);
FORCEPROP 1 LAST COMMENT_BODY TRUE
J 0
(-3775 3250);
DISPLAY 0.936170 (-3775 3250);
PAINT GREEN (-3775 3250);
DISPLAY INVISIBLE (-3775 3250);
FORCEPROP 2 LAST PATH I163
J 0
(-3850 3425);
DISPLAY 0.787234 (-3850 3425);
PAINT MONO (-3850 3425);
DISPLAY INVISIBLE (-3850 3425);
FORCEADD OFFPAGE..1
(-3900 3100);
FORCEPROP 2 LAST $XR0 59 
J 0
(-4121 3100);
DISPLAY 0.638298 (-4121 3100);
PAINT MONO (-4121 3100);
FORCEPROP 2 LAST $XR1 81 
J 0
(-4211 3100);
DISPLAY 0.638298 (-4211 3100);
PAINT MONO (-4211 3100);
FORCEPROP 2 LAST CDS_LIB mstr_standard
J 0
(-3900 3100);
DISPLAY 0.787234 (-3900 3100);
PAINT MONO (-3900 3100);
DISPLAY INVISIBLE (-3900 3100);
FORCEPROP 1 LAST OFFPAGE TRUE
J 0
(-3575 2975);
DISPLAY 0.936170 (-3575 2975);
PAINT GREEN (-3575 2975);
DISPLAY INVISIBLE (-3575 2975);
FORCEPROP 1 LAST COMMENT_BODY TRUE
J 0
(-3775 3000);
DISPLAY 0.936170 (-3775 3000);
PAINT GREEN (-3775 3000);
DISPLAY INVISIBLE (-3775 3000);
FORCEPROP 2 LAST PATH I164
J 0
(-3850 3175);
DISPLAY 0.787234 (-3850 3175);
PAINT MONO (-3850 3175);
DISPLAY INVISIBLE (-3850 3175);
FORCEADD TAP..6
(-3300 3000);
FORCEPROP 3 LASTPIN (-3250 3000) SIG_NAME M_J_CKE<2>
J 0
(-3240 3010);
DISPLAY 0.659574 (-3240 3010);
PAINT MONO (-3240 3010);
DISPLAY INVISIBLE (-3240 3010);
FORCEPROP 1 LASTPIN (-3250 3000) BN 2
J 0
(-3300 3010);
DISPLAY 0.617021 (-3300 3010);
PAINT PINK (-3300 3010);
FORCEPROP 2 LAST CDS_LIB mstr_standard
J 0
(-3300 3000);
DISPLAY 0.787234 (-3300 3000);
PAINT MONO (-3300 3000);
DISPLAY INVISIBLE (-3300 3000);
FORCEPROP 1 LAST BODY_TYPE PLUMBING
J 0
(-3300 2950);
DISPLAY 1.234043 (-3300 2950);
PAINT GREEN (-3300 2950);
DISPLAY INVISIBLE (-3300 2950);
FORCEPROP 1 LAST HDL_TAP TRUE
J 0
(-2975 2875);
DISPLAY 1.234043 (-2975 2875);
PAINT GREEN (-2975 2875);
DISPLAY INVISIBLE (-2975 2875);
FORCEPROP 1 LAST PATH I165
J 0
(-3300 3000);
DISPLAY 0.936170 (-3300 3000);
PAINT GREEN (-3300 3000);
DISPLAY INVISIBLE (-3300 3000);
FORCEADD TAP..6
(-3300 2900);
FORCEPROP 3 LASTPIN (-3250 2900) SIG_NAME M_J_ODT<3>
J 0
(-3240 2910);
DISPLAY 0.659574 (-3240 2910);
PAINT MONO (-3240 2910);
DISPLAY INVISIBLE (-3240 2910);
FORCEPROP 1 LASTPIN (-3250 2900) BN 3
J 0
(-3300 2910);
DISPLAY 0.617021 (-3300 2910);
PAINT PINK (-3300 2910);
FORCEPROP 2 LAST CDS_LIB mstr_standard
J 0
(-3300 2900);
DISPLAY 0.787234 (-3300 2900);
PAINT MONO (-3300 2900);
DISPLAY INVISIBLE (-3300 2900);
FORCEPROP 1 LAST BODY_TYPE PLUMBING
J 0
(-3300 2850);
DISPLAY 1.234043 (-3300 2850);
PAINT GREEN (-3300 2850);
DISPLAY INVISIBLE (-3300 2850);
FORCEPROP 1 LAST HDL_TAP TRUE
J 0
(-2975 2775);
DISPLAY 1.234043 (-2975 2775);
PAINT GREEN (-2975 2775);
DISPLAY INVISIBLE (-2975 2775);
FORCEPROP 1 LAST PATH I166
J 0
(-3300 2900);
DISPLAY 0.936170 (-3300 2900);
PAINT GREEN (-3300 2900);
DISPLAY INVISIBLE (-3300 2900);
FORCEADD OFFPAGE..1
(-3900 2950);
FORCEPROP 2 LAST $XR0 59 
J 0
(-4121 2950);
DISPLAY 0.638298 (-4121 2950);
PAINT MONO (-4121 2950);
FORCEPROP 2 LAST $XR1 81 
J 0
(-4211 2950);
DISPLAY 0.638298 (-4211 2950);
PAINT MONO (-4211 2950);
FORCEPROP 2 LAST CDS_LIB mstr_standard
J 0
(-3900 2950);
DISPLAY 0.787234 (-3900 2950);
PAINT MONO (-3900 2950);
DISPLAY INVISIBLE (-3900 2950);
FORCEPROP 1 LAST OFFPAGE TRUE
J 0
(-3575 2825);
DISPLAY 0.936170 (-3575 2825);
PAINT GREEN (-3575 2825);
DISPLAY INVISIBLE (-3575 2825);
FORCEPROP 1 LAST COMMENT_BODY TRUE
J 0
(-3775 2850);
DISPLAY 0.936170 (-3775 2850);
PAINT GREEN (-3775 2850);
DISPLAY INVISIBLE (-3775 2850);
FORCEPROP 2 LAST PATH I167
J 0
(-3850 3025);
DISPLAY 0.787234 (-3850 3025);
PAINT MONO (-3850 3025);
DISPLAY INVISIBLE (-3850 3025);
FORCEADD TAP..6
(-3300 2850);
FORCEPROP 3 LASTPIN (-3250 2850) SIG_NAME M_J_ODT<2>
J 0
(-3240 2860);
DISPLAY 0.659574 (-3240 2860);
PAINT MONO (-3240 2860);
DISPLAY INVISIBLE (-3240 2860);
FORCEPROP 1 LASTPIN (-3250 2850) BN 2
J 0
(-3300 2860);
DISPLAY 0.617021 (-3300 2860);
PAINT PINK (-3300 2860);
FORCEPROP 2 LAST CDS_LIB mstr_standard
J 0
(-3300 2850);
DISPLAY 0.787234 (-3300 2850);
PAINT MONO (-3300 2850);
DISPLAY INVISIBLE (-3300 2850);
FORCEPROP 1 LAST BODY_TYPE PLUMBING
J 0
(-3300 2800);
DISPLAY 1.234043 (-3300 2800);
PAINT GREEN (-3300 2800);
DISPLAY INVISIBLE (-3300 2800);
FORCEPROP 1 LAST HDL_TAP TRUE
J 0
(-2975 2725);
DISPLAY 1.234043 (-2975 2725);
PAINT GREEN (-2975 2725);
DISPLAY INVISIBLE (-2975 2725);
FORCEPROP 1 LAST PATH I168
J 0
(-3300 2850);
DISPLAY 0.936170 (-3300 2850);
PAINT GREEN (-3300 2850);
DISPLAY INVISIBLE (-3300 2850);
FORCEADD TAP..6
R 2
(850 4600);
FORCEPROP 3 LASTPIN (800 4600) SIG_NAME M_J_DQS_DN<12>
J 0
(810 4610);
DISPLAY 0.659574 (810 4610);
PAINT MONO (810 4610);
DISPLAY INVISIBLE (810 4610);
FORCEPROP 1 LASTPIN (800 4600) BN 12
J 2
(850 4610);
DISPLAY 0.617021 (850 4610);
PAINT PINK (850 4610);
FORCEPROP 2 LAST CDS_LIB mstr_standard
J 0
(850 4600);
DISPLAY 0.787234 (850 4600);
PAINT MONO (850 4600);
DISPLAY INVISIBLE (850 4600);
FORCEPROP 1 LAST BODY_TYPE PLUMBING
J 2
(850 4550);
DISPLAY 1.234043 (850 4550);
PAINT GREEN (850 4550);
DISPLAY INVISIBLE (850 4550);
FORCEPROP 1 LAST HDL_TAP TRUE
J 2
(525 4475);
DISPLAY 1.234043 (525 4475);
PAINT GREEN (525 4475);
DISPLAY INVISIBLE (525 4475);
FORCEPROP 1 LAST PATH I17
J 2
(850 4600);
DISPLAY 0.936170 (850 4600);
PAINT GREEN (850 4600);
DISPLAY INVISIBLE (850 4600);
FORCEADD SCONN288_H44441003..4
(-350 2050);
FORCEPROP 1 LAST LOCATION J9U2
J 0
(-800 3150);
DISPLAY 0.617021 (-800 3150);
PAINT AQUA (-800 3150);
FORCEPROP 1 LAST PART_NUMBER H44441-003
J 0
(-800 1000);
DISPLAY 0.617021 (-800 1000);
PAINT BLUE (-800 1000);
FORCEPROP 1 LAST MATERIAL SCONN
J 0
(-800 3100);
DISPLAY 0.617021 (-800 3100);
PAINT SKYBLUE (-800 3100);
FORCEPROP 2 LASTPIN (-850 2600) $PN 77
J 2
(-860 2610);
DISPLAY 0.617021 (-860 2610);
PAINT ORANGE (-860 2610);
FORCEPROP 2 LASTPIN (-850 2550) $PN 221
J 2
(-860 2560);
DISPLAY 0.617021 (-860 2560);
PAINT ORANGE (-860 2560);
FORCEPROP 2 LASTPIN (-850 2900) $PN 142
J 2
(-860 2910);
DISPLAY 0.617021 (-860 2910);
PAINT ORANGE (-860 2910);
FORCEPROP 2 LASTPIN (-850 2850) $PN 143
J 2
(-860 2860);
DISPLAY 0.617021 (-860 2860);
PAINT ORANGE (-860 2860);
FORCEPROP 2 LASTPIN (-850 2800) $PN 288
J 2
(-860 2810);
DISPLAY 0.617021 (-860 2810);
PAINT ORANGE (-860 2810);
FORCEPROP 2 LASTPIN (-850 2750) $PN 286
J 2
(-860 2760);
DISPLAY 0.617021 (-860 2760);
PAINT ORANGE (-860 2760);
FORCEPROP 2 LASTPIN (-850 2700) $PN 287
J 2
(-860 2710);
DISPLAY 0.617021 (-860 2710);
PAINT ORANGE (-860 2710);
FORCEPROP 2 LASTPIN (-850 2450) $PN 59
J 2
(-860 2460);
DISPLAY 0.617021 (-860 2460);
PAINT ORANGE (-860 2460);
FORCEPROP 2 LASTPIN (-850 2400) $PN 61
J 2
(-860 2410);
DISPLAY 0.617021 (-860 2410);
PAINT ORANGE (-860 2410);
FORCEPROP 2 LASTPIN (-850 2350) $PN 64
J 2
(-860 2360);
DISPLAY 0.617021 (-860 2360);
PAINT ORANGE (-860 2360);
FORCEPROP 2 LASTPIN (-850 2300) $PN 67
J 2
(-860 2310);
DISPLAY 0.617021 (-860 2310);
PAINT ORANGE (-860 2310);
FORCEPROP 2 LASTPIN (-850 2250) $PN 70
J 2
(-860 2260);
DISPLAY 0.617021 (-860 2260);
PAINT ORANGE (-860 2260);
FORCEPROP 2 LASTPIN (-850 2200) $PN 73
J 2
(-860 2210);
DISPLAY 0.617021 (-860 2210);
PAINT ORANGE (-860 2210);
FORCEPROP 2 LASTPIN (-850 2150) $PN 76
J 2
(-860 2160);
DISPLAY 0.617021 (-860 2160);
PAINT ORANGE (-860 2160);
FORCEPROP 2 LASTPIN (-850 2100) $PN 80
J 2
(-860 2110);
DISPLAY 0.617021 (-860 2110);
PAINT ORANGE (-860 2110);
FORCEPROP 2 LASTPIN (-850 2050) $PN 83
J 2
(-860 2060);
DISPLAY 0.617021 (-860 2060);
PAINT ORANGE (-860 2060);
FORCEPROP 2 LASTPIN (-850 2000) $PN 85
J 2
(-860 2010);
DISPLAY 0.617021 (-860 2010);
PAINT ORANGE (-860 2010);
FORCEPROP 2 LASTPIN (-850 1950) $PN 88
J 2
(-860 1960);
DISPLAY 0.617021 (-860 1960);
PAINT ORANGE (-860 1960);
FORCEPROP 2 LASTPIN (-850 1900) $PN 90
J 2
(-860 1910);
DISPLAY 0.617021 (-860 1910);
PAINT ORANGE (-860 1910);
FORCEPROP 2 LASTPIN (-850 1850) $PN 92
J 2
(-860 1860);
DISPLAY 0.617021 (-860 1860);
PAINT ORANGE (-860 1860);
FORCEPROP 2 LASTPIN (-850 1800) $PN 204
J 2
(-860 1810);
DISPLAY 0.617021 (-860 1810);
PAINT ORANGE (-860 1810);
FORCEPROP 2 LASTPIN (-850 1750) $PN 206
J 2
(-860 1760);
DISPLAY 0.617021 (-860 1760);
PAINT ORANGE (-860 1760);
FORCEPROP 2 LASTPIN (-850 1700) $PN 209
J 2
(-860 1710);
DISPLAY 0.617021 (-860 1710);
PAINT ORANGE (-860 1710);
FORCEPROP 2 LASTPIN (-850 1650) $PN 212
J 2
(-860 1660);
DISPLAY 0.617021 (-860 1660);
PAINT ORANGE (-860 1660);
FORCEPROP 2 LASTPIN (-850 1600) $PN 215
J 2
(-860 1610);
DISPLAY 0.617021 (-860 1610);
PAINT ORANGE (-860 1610);
FORCEPROP 2 LASTPIN (-850 1550) $PN 217
J 2
(-860 1560);
DISPLAY 0.617021 (-860 1560);
PAINT ORANGE (-860 1560);
FORCEPROP 2 LASTPIN (-850 1500) $PN 220
J 2
(-860 1510);
DISPLAY 0.617021 (-860 1510);
PAINT ORANGE (-860 1510);
FORCEPROP 2 LASTPIN (-850 1450) $PN 223
J 2
(-860 1460);
DISPLAY 0.617021 (-860 1460);
PAINT ORANGE (-860 1460);
FORCEPROP 2 LASTPIN (-850 1400) $PN 226
J 2
(-860 1410);
DISPLAY 0.617021 (-860 1410);
PAINT ORANGE (-860 1410);
FORCEPROP 2 LASTPIN (-850 1350) $PN 229
J 2
(-860 1360);
DISPLAY 0.617021 (-860 1360);
PAINT ORANGE (-860 1360);
FORCEPROP 2 LASTPIN (-850 1300) $PN 231
J 2
(-860 1310);
DISPLAY 0.617021 (-860 1310);
PAINT ORANGE (-860 1310);
FORCEPROP 2 LASTPIN (-850 1250) $PN 233
J 2
(-860 1260);
DISPLAY 0.617021 (-860 1260);
PAINT ORANGE (-860 1260);
FORCEPROP 2 LASTPIN (-850 1200) $PN 236
J 2
(-860 1210);
DISPLAY 0.617021 (-860 1210);
PAINT ORANGE (-860 1210);
FORCEPROP 2 LASTPIN (150 2900) $PN 1
J 0
(160 2910);
DISPLAY 0.617021 (160 2910);
PAINT ORANGE (160 2910);
FORCEPROP 2 LASTPIN (150 2850) $PN 145
J 0
(160 2860);
DISPLAY 0.617021 (160 2860);
PAINT ORANGE (160 2860);
FORCEPROP 1 LAST PACK_TYPE PIP
J 0
(-800 3200);
PAINT SKYBLUE (-800 3200);
DISPLAY INVISIBLE (-800 3200);
FORCEPROP 2 LAST BOM_COST MEM
J 0
(-350 2050);
PAINT ORANGE (-350 2050);
DISPLAY INVISIBLE (-350 2050);
FORCEPROP 2 LAST CDS_LIB mstr_sconn
J 0
(-350 2050);
PAINT ORANGE (-350 2050);
DISPLAY INVISIBLE (-350 2050);
FORCEPROP 2 LAST SEC_TYPE PIP
J 0
(-800 3200);
DISPLAY 1.021277 (-800 3200);
PAINT ORANGE (-800 3200);
DISPLAY INVISIBLE (-800 3200);
FORCEPROP 2 LAST SEC 4
J 0
(-800 3200);
DISPLAY 0.680851 (-800 3200);
PAINT MONO (-800 3200);
DISPLAY INVISIBLE (-800 3200);
FORCEPROP 2 LAST CDS_LOCATION J9U2
J 0
(-800 3150);
DISPLAY 0.617021 (-800 3150);
PAINT AQUA (-800 3150);
DISPLAY INVISIBLE (-800 3150);
FORCEPROP 1 LAST PATH I171
J 0
(-350 3100);
PAINT GREEN (-350 3100);
DISPLAY INVISIBLE (-350 3100);
FORCEPROP 2 LAST ROOM DDR4_CH_J
J 0
(-350 2050);
PAINT ORANGE (-350 2050);
DISPLAY INVISIBLE (-350 2050);
FORCEADD GND..1
R 2
(2450 1050);
FORCEPROP 3 LASTPIN (2450 1100) SIG_NAME GND\g
J 0
(2460 1110);
DISPLAY 0.659574 (2460 1110);
PAINT MONO (2460 1110);
DISPLAY INVISIBLE (2460 1110);
FORCEPROP 1 LAST VOLTAGE 0
J 0
(2450 1050);
PAINT SKYBLUE (2450 1050);
DISPLAY INVISIBLE (2450 1050);
FORCEPROP 1 LAST SIZE 1B
J 2
(2375 1000);
DISPLAY 1.170213 (2375 1000);
PAINT GREEN (2375 1000);
DISPLAY INVISIBLE (2375 1000);
FORCEPROP 2 LAST CDS_LIB mstr_symbols
J 0
(2450 1050);
DISPLAY 0.787234 (2450 1050);
PAINT MONO (2450 1050);
DISPLAY INVISIBLE (2450 1050);
FORCEPROP 2 LAST BOM_COST MEM
J 0
(2450 1055);
PAINT ORANGE (2450 1055);
DISPLAY INVISIBLE (2450 1055);
FORCEPROP 1 LAST BODY_TYPE PLUMBING
J 2
(2495 1007);
DISPLAY 0.340426 (2495 1007);
PAINT GREEN (2495 1007);
DISPLAY INVISIBLE (2495 1007);
FORCEPROP 1 LAST PATH I172
J 2
(2375 1050);
DISPLAY 1.404255 (2375 1050);
PAINT GREEN (2375 1050);
DISPLAY INVISIBLE (2375 1050);
FORCEPROP 2 LAST ROOM DDR4_CH_J
J 0
(2450 1055);
PAINT ORANGE (2450 1055);
DISPLAY INVISIBLE (2450 1055);
FORCEPROP 1 LAST HDL_POWER GND
J 2
(2450 1200);
DISPLAY 0.553191 (2450 1200);
PAINT GREEN (2450 1200);
DISPLAY INVISIBLE (2450 1200);
FORCEADD OFFPAGE..1
(-3900 1750);
FORCEPROP 2 LAST $XR0 99 
J 0
(-4181 1750);
DISPLAY 0.638298 (-4181 1750);
PAINT MONO (-4181 1750);
FORCEPROP 2 LAST $XR1 77 
J 0
(-4271 1750);
DISPLAY 0.638298 (-4271 1750);
PAINT MONO (-4271 1750);
FORCEPROP 2 LAST $XR2 78 
J 0
(-4361 1750);
DISPLAY 0.638298 (-4361 1750);
PAINT MONO (-4361 1750);
FORCEPROP 2 LAST $XR3 79 
J 0
(-4451 1750);
DISPLAY 0.638298 (-4451 1750);
PAINT MONO (-4451 1750);
FORCEPROP 2 LAST $XR4 80 
J 0
(-4541 1750);
DISPLAY 0.638298 (-4541 1750);
PAINT MONO (-4541 1750);
FORCEPROP 2 LAST $XR5 81 
J 0
(-4631 1750);
DISPLAY 0.638298 (-4631 1750);
PAINT MONO (-4631 1750);
FORCEPROP 2 LAST CDS_LIB mstr_standard
J 0
(-3900 1750);
DISPLAY 0.787234 (-3900 1750);
PAINT MONO (-3900 1750);
DISPLAY INVISIBLE (-3900 1750);
FORCEPROP 1 LAST OFFPAGE TRUE
J 0
(-3575 1625);
DISPLAY 0.936170 (-3575 1625);
PAINT GREEN (-3575 1625);
DISPLAY INVISIBLE (-3575 1625);
FORCEPROP 1 LAST COMMENT_BODY TRUE
J 0
(-3775 1650);
DISPLAY 0.936170 (-3775 1650);
PAINT GREEN (-3775 1650);
DISPLAY INVISIBLE (-3775 1650);
FORCEPROP 2 LAST PATH I173
J 0
(-4175 1800);
DISPLAY 0.787234 (-4175 1800);
PAINT ORANGE (-4175 1800);
DISPLAY INVISIBLE (-4175 1800);
FORCEADD OFFPAGE..6
(-3900 1800);
FORCEPROP 2 LAST $XR0 77 
J 0
(-4179 1800);
DISPLAY 0.638298 (-4179 1800);
PAINT MONO (-4179 1800);
FORCEPROP 2 LAST $XR1 78 
J 0
(-4269 1800);
DISPLAY 0.638298 (-4269 1800);
PAINT MONO (-4269 1800);
FORCEPROP 2 LAST $XR2 79 
J 0
(-4359 1800);
DISPLAY 0.638298 (-4359 1800);
PAINT MONO (-4359 1800);
FORCEPROP 2 LAST $XR3 80 
J 0
(-4449 1800);
DISPLAY 0.638298 (-4449 1800);
PAINT MONO (-4449 1800);
FORCEPROP 2 LAST $XR4 81 
J 0
(-4539 1800);
DISPLAY 0.638298 (-4539 1800);
PAINT MONO (-4539 1800);
FORCEPROP 2 LAST $XR5 99 
J 0
(-4629 1800);
DISPLAY 0.638298 (-4629 1800);
PAINT MONO (-4629 1800);
FORCEPROP 2 LASTPIN (-3850 1800) SIG_NAME SMB_DDR_GHJ_VPP_SDA
J 0
(-3810 1810);
DISPLAY 0.617021 (-3810 1810);
PAINT ORANGE (-3810 1810);
FORCEPROP 2 LAST CDS_LIB mstr_standard
J 0
(-3900 1800);
DISPLAY 0.787234 (-3900 1800);
PAINT MONO (-3900 1800);
DISPLAY INVISIBLE (-3900 1800);
FORCEPROP 1 LAST OFFPAGE TRUE
J 0
(-3575 1675);
DISPLAY 0.936170 (-3575 1675);
PAINT GREEN (-3575 1675);
DISPLAY INVISIBLE (-3575 1675);
FORCEPROP 1 LAST COMMENT_BODY TRUE
J 0
(-3800 1725);
DISPLAY 0.936170 (-3800 1725);
PAINT GREEN (-3800 1725);
DISPLAY INVISIBLE (-3800 1725);
FORCEPROP 2 LAST PATH I174
J 0
(-4225 1850);
DISPLAY 0.787234 (-4225 1850);
PAINT ORANGE (-4225 1850);
DISPLAY INVISIBLE (-4225 1850);
FORCEADD OFFPAGE..1
(-4650 1650);
FORCEPROP 2 LAST $XR0 100 
J 0
(-4902 1650);
DISPLAY 0.638298 (-4902 1650);
PAINT MONO (-4902 1650);
FORCEPROP 2 LAST $XR1 81 
J 0
(-4992 1650);
DISPLAY 0.638298 (-4992 1650);
PAINT MONO (-4992 1650);
FORCEPROP 2 LAST CDS_LIB mstr_standard
J 0
(-4650 1650);
DISPLAY 0.787234 (-4650 1650);
PAINT MONO (-4650 1650);
DISPLAY INVISIBLE (-4650 1650);
FORCEPROP 1 LAST OFFPAGE TRUE
J 0
(-4325 1525);
DISPLAY 0.936170 (-4325 1525);
PAINT GREEN (-4325 1525);
DISPLAY INVISIBLE (-4325 1525);
FORCEPROP 1 LAST COMMENT_BODY TRUE
J 0
(-4525 1550);
DISPLAY 0.936170 (-4525 1550);
PAINT GREEN (-4525 1550);
DISPLAY INVISIBLE (-4525 1550);
FORCEPROP 2 LAST PATH I175
J 0
(-4900 1700);
DISPLAY 0.787234 (-4900 1700);
PAINT ORANGE (-4900 1700);
DISPLAY INVISIBLE (-4900 1700);
FORCEADD OFFPAGE..5
(-4325 2450);
FORCEPROP 2 LAST $XR0 43 
J 0
(-4579 2450);
DISPLAY 0.638298 (-4579 2450);
PAINT MONO (-4579 2450);
FORCEPROP 2 LAST $XR1 44 
J 0
(-4669 2450);
DISPLAY 0.638298 (-4669 2450);
PAINT MONO (-4669 2450);
FORCEPROP 2 LAST $XR2 45 
J 0
(-4759 2450);
DISPLAY 0.638298 (-4759 2450);
PAINT MONO (-4759 2450);
FORCEPROP 2 LAST $XR3 46 
J 0
(-4849 2450);
DISPLAY 0.638298 (-4849 2450);
PAINT MONO (-4849 2450);
FORCEPROP 2 LAST $XR4 47 
J 0
(-4939 2450);
DISPLAY 0.638298 (-4939 2450);
PAINT MONO (-4939 2450);
FORCEPROP 2 LAST $XR5 48 
J 0
(-5029 2450);
DISPLAY 0.638298 (-5029 2450);
PAINT MONO (-5029 2450);
FORCEPROP 2 LAST $XR6 49 
J 0
(-5119 2450);
DISPLAY 0.638298 (-5119 2450);
PAINT MONO (-5119 2450);
FORCEPROP 2 LAST $XR7 50 
J 0
(-5209 2450);
DISPLAY 0.638298 (-5209 2450);
PAINT MONO (-5209 2450);
FORCEPROP 2 LAST $XR8 51 
J 0
(-5299 2450);
DISPLAY 0.638298 (-5299 2450);
PAINT MONO (-5299 2450);
FORCEPROP 2 LAST $XR9 52 
J 0
(-4579 2414);
DISPLAY 0.638298 (-4579 2414);
PAINT MONO (-4579 2414);
FORCEPROP 2 LAST $XR10 53 
J 0
(-4669 2414);
DISPLAY 0.638298 (-4669 2414);
PAINT MONO (-4669 2414);
FORCEPROP 2 LAST $XR11 54 
J 0
(-4759 2414);
DISPLAY 0.638298 (-4759 2414);
PAINT MONO (-4759 2414);
FORCEPROP 2 LAST $XR12 77 
J 0
(-4849 2414);
DISPLAY 0.638298 (-4849 2414);
PAINT MONO (-4849 2414);
FORCEPROP 2 LAST $XR13 78 
J 0
(-4939 2414);
DISPLAY 0.638298 (-4939 2414);
PAINT MONO (-4939 2414);
FORCEPROP 2 LAST $XR14 79 
J 0
(-5029 2414);
DISPLAY 0.638298 (-5029 2414);
PAINT MONO (-5029 2414);
FORCEPROP 2 LAST $XR15 80 
J 0
(-5119 2414);
DISPLAY 0.638298 (-5119 2414);
PAINT MONO (-5119 2414);
FORCEPROP 2 LAST $XR16 81 
J 0
(-5209 2414);
DISPLAY 0.638298 (-5209 2414);
PAINT MONO (-5209 2414);
FORCEPROP 2 LAST $XR17 83 
J 0
(-5299 2414);
DISPLAY 0.638298 (-5299 2414);
PAINT MONO (-5299 2414);
FORCEPROP 2 LAST $XR18 84 
J 0
(-4579 2486);
DISPLAY 0.638298 (-4579 2486);
PAINT MONO (-4579 2486);
FORCEPROP 2 LAST $XR19 85 
J 0
(-4669 2486);
DISPLAY 0.638298 (-4669 2486);
PAINT MONO (-4669 2486);
FORCEPROP 2 LAST $XR20 86 
J 0
(-4759 2486);
DISPLAY 0.638298 (-4759 2486);
PAINT MONO (-4759 2486);
FORCEPROP 2 LAST $XR21 87 
J 0
(-4849 2486);
DISPLAY 0.638298 (-4849 2486);
PAINT MONO (-4849 2486);
FORCEPROP 2 LAST $XR22 88 
J 0
(-4939 2486);
DISPLAY 0.638298 (-4939 2486);
PAINT MONO (-4939 2486);
FORCEPROP 2 LAST $XR23 94 
J 0
(-5029 2486);
DISPLAY 0.638298 (-5029 2486);
PAINT MONO (-5029 2486);
FORCEPROP 2 LAST CDS_LIB mstr_standard
J 0
(-4325 2450);
DISPLAY 0.787234 (-4325 2450);
PAINT MONO (-4325 2450);
DISPLAY INVISIBLE (-4325 2450);
FORCEPROP 1 LAST OFFPAGE TRUE
J 0
(-4000 2325);
DISPLAY 1.404255 (-4000 2325);
PAINT GREEN (-4000 2325);
DISPLAY INVISIBLE (-4000 2325);
FORCEPROP 1 LAST COMMENT_BODY TRUE
J 0
(-4225 2375);
DISPLAY 1.404255 (-4225 2375);
PAINT GREEN (-4225 2375);
DISPLAY INVISIBLE (-4225 2375);
FORCEPROP 2 LAST PATH I178
J 0
(-4275 2525);
DISPLAY 0.787234 (-4275 2525);
PAINT ORANGE (-4275 2525);
DISPLAY INVISIBLE (-4275 2525);
FORCEADD GND..1
(-4500 1150);
FORCEPROP 3 LASTPIN (-4500 1200) SIG_NAME GND\g
J 0
(-4490 1210);
DISPLAY 0.659574 (-4490 1210);
PAINT MONO (-4490 1210);
DISPLAY INVISIBLE (-4490 1210);
FORCEPROP 1 LAST VOLTAGE 0
J 0
(-4500 1150);
PAINT SKYBLUE (-4500 1150);
DISPLAY INVISIBLE (-4500 1150);
FORCEPROP 2 LAST CDS_LIB mstr_symbols
J 0
(-4500 1150);
PAINT ORANGE (-4500 1150);
DISPLAY INVISIBLE (-4500 1150);
FORCEPROP 1 LAST SIZE 1B
J 0
(-4425 1100);
DISPLAY 1.787234 (-4425 1100);
PAINT GREEN (-4425 1100);
DISPLAY INVISIBLE (-4425 1100);
FORCEPROP 2 LAST BOM_COST MEM
J 0
(-4500 1155);
PAINT ORANGE (-4500 1155);
DISPLAY INVISIBLE (-4500 1155);
FORCEPROP 1 LAST BODY_TYPE PLUMBING
J 0
(-4545 1107);
DISPLAY 0.340426 (-4545 1107);
PAINT GREEN (-4545 1107);
DISPLAY INVISIBLE (-4545 1107);
FORCEPROP 1 LAST PATH I179
J 0
(-4425 1150);
DISPLAY 1.404255 (-4425 1150);
PAINT GREEN (-4425 1150);
DISPLAY INVISIBLE (-4425 1150);
FORCEPROP 2 LAST ROOM DDR4_CH_J
J 0
(-4500 1155);
PAINT ORANGE (-4500 1155);
DISPLAY INVISIBLE (-4500 1155);
FORCEPROP 1 LAST HDL_POWER GND
J 0
(-4500 1300);
DISPLAY 1.404255 (-4500 1300);
PAINT GREEN (-4500 1300);
DISPLAY INVISIBLE (-4500 1300);
FORCEADD TAP..6
R 2
(850 4500);
FORCEPROP 3 LASTPIN (800 4500) SIG_NAME M_J_DQS_DN<11>
J 0
(810 4510);
DISPLAY 0.659574 (810 4510);
PAINT MONO (810 4510);
DISPLAY INVISIBLE (810 4510);
FORCEPROP 1 LASTPIN (800 4500) BN 11
J 2
(850 4510);
DISPLAY 0.617021 (850 4510);
PAINT PINK (850 4510);
FORCEPROP 2 LAST CDS_LIB mstr_standard
J 0
(850 4500);
DISPLAY 0.787234 (850 4500);
PAINT MONO (850 4500);
DISPLAY INVISIBLE (850 4500);
FORCEPROP 1 LAST BODY_TYPE PLUMBING
J 2
(850 4450);
DISPLAY 1.234043 (850 4450);
PAINT GREEN (850 4450);
DISPLAY INVISIBLE (850 4450);
FORCEPROP 1 LAST HDL_TAP TRUE
J 2
(525 4375);
DISPLAY 1.234043 (525 4375);
PAINT GREEN (525 4375);
DISPLAY INVISIBLE (525 4375);
FORCEPROP 1 LAST PATH I18
J 2
(850 4500);
DISPLAY 0.936170 (850 4500);
PAINT GREEN (850 4500);
DISPLAY INVISIBLE (850 4500);
FORCEADD CAP_A..1
R 2
(-4500 1450);
FORCEPROP 1 LAST LOCATION C1G19
J 2
(-4550 1550);
DISPLAY 0.617021 (-4550 1550);
PAINT AQUA (-4550 1550);
FORCEPROP 1 LAST PART_NUMBER A36096-045
J 2
(-4550 1300);
DISPLAY 0.617021 (-4550 1300);
PAINT BLUE (-4550 1300);
FORCEPROP 1 LAST VALUE 0.01UF
J 2
(-4550 1500);
DISPLAY 0.617021 (-4550 1500);
PAINT SKYBLUE (-4550 1500);
FORCEPROP 1 LAST TOLERANCE 10%
J 2
(-4550 1400);
DISPLAY 0.617021 (-4550 1400);
PAINT SKYBLUE (-4550 1400);
FORCEPROP 1 LAST PACK_TYPE 0402V
J 2
(-4550 1250);
DISPLAY 0.617021 (-4550 1250);
PAINT SKYBLUE (-4550 1250);
FORCEPROP 1 LAST VOLTAGE 25V
J 2
(-4550 1450);
DISPLAY 0.617021 (-4550 1450);
PAINT SKYBLUE (-4550 1450);
FORCEPROP 1 LAST MATERIAL X7R
J 2
(-4550 1350);
DISPLAY 0.617021 (-4550 1350);
PAINT SKYBLUE (-4550 1350);
FORCEPROP 2 LAST CDS_LOCATION C1G19
J 2
(-4550 1550);
DISPLAY 0.617021 (-4550 1550);
PAINT AQUA (-4550 1550);
DISPLAY INVISIBLE (-4550 1550);
FORCEPROP 2 LAST BOM_COST MEM
J 0
(-4500 1450);
PAINT ORANGE (-4500 1450);
DISPLAY INVISIBLE (-4500 1450);
FORCEPROP 2 LAST CDS_LIB dev_discrete
J 0
(-4500 1450);
PAINT ORANGE (-4500 1450);
DISPLAY INVISIBLE (-4500 1450);
FORCEPROP 2 LAST CDS_SEC 1
J 2
(-4550 1650);
PAINT MONO (-4550 1650);
DISPLAY INVISIBLE (-4550 1650);
FORCEPROP 2 LAST $SEC 1
J 0
(-4550 1650);
PAINT MONO (-4550 1650);
DISPLAY INVISIBLE (-4550 1650);
FORCEPROP 1 LAST PATH I180
J 2
(-4550 1600);
DISPLAY 0.978723 (-4550 1600);
PAINT WHITE (-4550 1600);
DISPLAY INVISIBLE (-4550 1600);
FORCEPROP 2 LAST ROOM DDR4_CH_J
J 0
(-4500 1450);
PAINT ORANGE (-4500 1450);
DISPLAY INVISIBLE (-4500 1450);
FORCEPROP 1 LASTPIN (-4500 1550) $PN 1
J 2
(-4510 1530);
DISPLAY 0.787234 (-4510 1530);
PAINT ORANGE (-4510 1530);
DISPLAY INVISIBLE (-4510 1530);
FORCEPROP 1 LASTPIN (-4500 1350) $PN 2
J 2
(-4510 1330);
DISPLAY 0.787234 (-4510 1330);
PAINT ORANGE (-4510 1330);
DISPLAY INVISIBLE (-4510 1330);
FORCEADD PVPP_GHJ..1
(-1050 3025);
FORCEPROP 3 LASTPIN (-1050 2975) SIG_NAME PVPP_GHJ\g
J 0
(-1040 2985);
DISPLAY 0.659574 (-1040 2985);
PAINT MONO (-1040 2985);
DISPLAY INVISIBLE (-1040 2985);
FORCEPROP 1 LAST VOLTAGE 2.5V
J 0
(-1095 2982);
DISPLAY 0.340426 (-1095 2982);
PAINT SKYBLUE (-1095 2982);
DISPLAY INVISIBLE (-1095 2982);
FORCEPROP 0 LAST BOM_COST MEM
J 0
(-1050 3125);
PAINT ORANGE (-1050 3125);
DISPLAY INVISIBLE (-1050 3125);
FORCEPROP 2 LAST CDS_LIB mstr_symbols
J 0
(-1050 3025);
PAINT ORANGE (-1050 3025);
DISPLAY INVISIBLE (-1050 3025);
FORCEPROP 1 LAST BODY_TYPE PLUMBING
J 0
(-1095 2982);
DISPLAY 0.340426 (-1095 2982);
PAINT GREEN (-1095 2982);
DISPLAY INVISIBLE (-1095 2982);
FORCEPROP 1 LAST PATH I181
J 0
(-1000 3050);
DISPLAY 0.872340 (-1000 3050);
PAINT AQUA (-1000 3050);
DISPLAY INVISIBLE (-1000 3050);
FORCEPROP 2 LAST ROOM DDR4_CH_K
J 0
(-1050 3125);
PAINT ORANGE (-1050 3125);
DISPLAY INVISIBLE (-1050 3125);
FORCEPROP 1 LAST HDL_POWER PVPP_GHJ
J 1
(-1050 3075);
DISPLAY 0.872340 (-1050 3075);
PAINT GREEN (-1050 3075);
DISPLAY INVISIBLE (-1050 3075);
FORCEADD PVPP_GHJ..1
(-5200 2150);
FORCEPROP 3 LASTPIN (-5200 2100) SIG_NAME PVPP_GHJ\g
J 0
(-5190 2110);
DISPLAY 0.659574 (-5190 2110);
PAINT MONO (-5190 2110);
DISPLAY INVISIBLE (-5190 2110);
FORCEPROP 1 LAST VOLTAGE 2.5V
J 0
(-5245 2107);
DISPLAY 0.340426 (-5245 2107);
PAINT SKYBLUE (-5245 2107);
DISPLAY INVISIBLE (-5245 2107);
FORCEPROP 0 LAST BOM_COST MEM
J 0
(-5200 2250);
PAINT ORANGE (-5200 2250);
DISPLAY INVISIBLE (-5200 2250);
FORCEPROP 2 LAST CDS_LIB mstr_symbols
J 0
(-5200 2150);
PAINT ORANGE (-5200 2150);
DISPLAY INVISIBLE (-5200 2150);
FORCEPROP 1 LAST BODY_TYPE PLUMBING
J 0
(-5245 2107);
DISPLAY 0.340426 (-5245 2107);
PAINT GREEN (-5245 2107);
DISPLAY INVISIBLE (-5245 2107);
FORCEPROP 1 LAST PATH I182
J 0
(-5150 2175);
DISPLAY 0.872340 (-5150 2175);
PAINT AQUA (-5150 2175);
DISPLAY INVISIBLE (-5150 2175);
FORCEPROP 2 LAST ROOM DDR4_CH_J
J 0
(-5200 2250);
PAINT ORANGE (-5200 2250);
DISPLAY INVISIBLE (-5200 2250);
FORCEPROP 1 LAST HDL_POWER PVPP_GHJ
J 1
(-5200 2200);
DISPLAY 0.872340 (-5200 2200);
PAINT GREEN (-5200 2200);
DISPLAY INVISIBLE (-5200 2200);
FORCEADD OFFPAGE..1
(-3900 1350);
FORCEPROP 2 LAST $XR0 89 
J 0
(-4121 1350);
DISPLAY 0.638298 (-4121 1350);
PAINT MONO (-4121 1350);
FORCEPROP 2 LAST $XR1 77 
J 0
(-4211 1350);
DISPLAY 0.638298 (-4211 1350);
PAINT MONO (-4211 1350);
FORCEPROP 2 LAST $XR2 78 
J 0
(-4301 1350);
DISPLAY 0.638298 (-4301 1350);
PAINT MONO (-4301 1350);
FORCEPROP 2 LAST $XR3 79 
J 0
(-4391 1350);
DISPLAY 0.638298 (-4391 1350);
PAINT MONO (-4391 1350);
FORCEPROP 2 LAST $XR4 80 
J 0
(-4481 1350);
DISPLAY 0.638298 (-4481 1350);
PAINT MONO (-4481 1350);
FORCEPROP 2 LAST $XR5 81 
J 0
(-4121 1314);
DISPLAY 0.638298 (-4121 1314);
PAINT MONO (-4121 1314);
FORCEPROP 2 LAST CDS_LIB mstr_standard
J 0
(-3900 1350);
PAINT ORANGE (-3900 1350);
DISPLAY INVISIBLE (-3900 1350);
FORCEPROP 1 LAST OFFPAGE TRUE
J 0
(-3575 1225);
DISPLAY 0.936170 (-3575 1225);
PAINT GREEN (-3575 1225);
DISPLAY INVISIBLE (-3575 1225);
FORCEPROP 1 LAST COMMENT_BODY TRUE
J 0
(-3775 1250);
DISPLAY 0.936170 (-3775 1250);
PAINT GREEN (-3775 1250);
DISPLAY INVISIBLE (-3775 1250);
FORCEPROP 2 LAST PATH I183
J 0
(-3850 1425);
PAINT ORANGE (-3850 1425);
DISPLAY INVISIBLE (-3850 1425);
FORCEADD SCONN288_H44441003..1
(-2500 3150);
FORCEPROP 1 LAST LOCATION J9U2
J 0
(-2950 5050);
DISPLAY 0.617021 (-2950 5050);
PAINT AQUA (-2950 5050);
FORCEPROP 1 LAST PART_NUMBER H44441-003
J 0
(-2950 1150);
DISPLAY 0.617021 (-2950 1150);
PAINT BLUE (-2950 1150);
FORCEPROP 1 LAST MATERIAL SCONN
J 0
(-2950 5000);
DISPLAY 0.617021 (-2950 5000);
PAINT SKYBLUE (-2950 5000);
FORCEPROP 2 LASTPIN (-3000 1650) $PN 146
J 2
(-3010 1660);
DISPLAY 0.617021 (-3010 1660);
PAINT ORANGE (-3010 1660);
FORCEPROP 2 LASTPIN (-3000 2000) $PN 284
J 2
(-3010 2010);
DISPLAY 0.617021 (-3010 2010);
PAINT ORANGE (-3010 2010);
FORCEPROP 2 LASTPIN (-3000 1800) $PN 285
J 2
(-3010 1810);
DISPLAY 0.617021 (-3010 1810);
PAINT ORANGE (-3010 1810);
FORCEPROP 2 LASTPIN (-3000 1750) $PN 141
J 2
(-3010 1760);
DISPLAY 0.617021 (-3010 1760);
PAINT ORANGE (-3010 1760);
FORCEPROP 2 LASTPIN (-3000 1350) $PN 230
J 2
(-3010 1360);
DISPLAY 0.617021 (-3010 1360);
PAINT ORANGE (-3010 1360);
FORCEPROP 2 LASTPIN (-3000 1950) $PN 238
J 2
(-3010 1960);
DISPLAY 0.617021 (-3010 1960);
PAINT ORANGE (-3010 1960);
FORCEPROP 2 LASTPIN (-3000 1900) $PN 140
J 2
(-3010 1910);
DISPLAY 0.617021 (-3010 1910);
PAINT ORANGE (-3010 1910);
FORCEPROP 2 LASTPIN (-3000 1850) $PN 139
J 2
(-3010 1860);
DISPLAY 0.617021 (-3010 1860);
PAINT ORANGE (-3010 1860);
FORCEPROP 2 LASTPIN (-3000 3300) $PN 237
J 2
(-3010 3310);
DISPLAY 0.617021 (-3010 3310);
PAINT ORANGE (-3010 3310);
FORCEPROP 2 LASTPIN (-3000 3250) $PN 93
J 2
(-3010 3260);
DISPLAY 0.617021 (-3010 3260);
PAINT ORANGE (-3010 3260);
FORCEPROP 2 LASTPIN (-3000 3200) $PN 89
J 2
(-3010 3210);
DISPLAY 0.617021 (-3010 3210);
PAINT ORANGE (-3010 3210);
FORCEPROP 2 LASTPIN (-3000 3150) $PN 84
J 2
(-3010 3160);
DISPLAY 0.617021 (-3010 3160);
PAINT ORANGE (-3010 3160);
FORCEPROP 2 LASTPIN (-3000 1550) $PN 144
J 2
(-3010 1560);
DISPLAY 0.617021 (-3010 1560);
PAINT ORANGE (-3010 1560);
FORCEPROP 2 LASTPIN (-3000 1500) $PN 227
J 2
(-3010 1510);
DISPLAY 0.617021 (-3010 1510);
PAINT ORANGE (-3010 1510);
FORCEPROP 2 LASTPIN (-3000 1450) $PN 205
J 2
(-3010 1460);
DISPLAY 0.617021 (-3010 1460);
PAINT ORANGE (-3010 1460);
FORCEPROP 2 LASTPIN (-3000 2250) $PN 58
J 2
(-3010 2260);
DISPLAY 0.617021 (-3010 2260);
PAINT ORANGE (-3010 2260);
FORCEPROP 2 LASTPIN (-3000 2300) $PN 222
J 2
(-3010 2310);
DISPLAY 0.617021 (-3010 2310);
PAINT ORANGE (-3010 2310);
FORCEPROP 2 LASTPIN (-3000 2900) $PN 91
J 2
(-3010 2910);
DISPLAY 0.617021 (-3010 2910);
PAINT ORANGE (-3010 2910);
FORCEPROP 2 LASTPIN (-3000 2850) $PN 87
J 2
(-3010 2860);
DISPLAY 0.617021 (-3010 2860);
PAINT ORANGE (-3010 2860);
FORCEPROP 2 LASTPIN (-3000 2200) $PN 78
J 2
(-3010 2210);
DISPLAY 0.617021 (-3010 2210);
PAINT ORANGE (-3010 2210);
FORCEPROP 2 LASTPIN (-2000 4800) $PN 280
J 0
(-1990 4810);
DISPLAY 0.617021 (-1990 4810);
PAINT ORANGE (-1990 4810);
FORCEPROP 2 LASTPIN (-2000 4750) $PN 135
J 0
(-1990 4760);
DISPLAY 0.617021 (-1990 4760);
PAINT ORANGE (-1990 4760);
FORCEPROP 2 LASTPIN (-2000 4700) $PN 273
J 0
(-1990 4710);
DISPLAY 0.617021 (-1990 4710);
PAINT ORANGE (-1990 4710);
FORCEPROP 2 LASTPIN (-2000 4650) $PN 128
J 0
(-1990 4660);
DISPLAY 0.617021 (-1990 4660);
PAINT ORANGE (-1990 4660);
FORCEPROP 2 LASTPIN (-2000 4600) $PN 282
J 0
(-1990 4610);
DISPLAY 0.617021 (-1990 4610);
PAINT ORANGE (-1990 4610);
FORCEPROP 2 LASTPIN (-2000 4550) $PN 137
J 0
(-1990 4560);
DISPLAY 0.617021 (-1990 4560);
PAINT ORANGE (-1990 4560);
FORCEPROP 2 LASTPIN (-2000 4500) $PN 275
J 0
(-1990 4510);
DISPLAY 0.617021 (-1990 4510);
PAINT ORANGE (-1990 4510);
FORCEPROP 2 LASTPIN (-2000 4450) $PN 130
J 0
(-1990 4460);
DISPLAY 0.617021 (-1990 4460);
PAINT ORANGE (-1990 4460);
FORCEPROP 2 LASTPIN (-2000 4400) $PN 269
J 0
(-1990 4410);
DISPLAY 0.617021 (-1990 4410);
PAINT ORANGE (-1990 4410);
FORCEPROP 2 LASTPIN (-2000 4350) $PN 124
J 0
(-1990 4360);
DISPLAY 0.617021 (-1990 4360);
PAINT ORANGE (-1990 4360);
FORCEPROP 2 LASTPIN (-2000 4300) $PN 262
J 0
(-1990 4310);
DISPLAY 0.617021 (-1990 4310);
PAINT ORANGE (-1990 4310);
FORCEPROP 2 LASTPIN (-2000 4250) $PN 117
J 0
(-1990 4260);
DISPLAY 0.617021 (-1990 4260);
PAINT ORANGE (-1990 4260);
FORCEPROP 2 LASTPIN (-2000 4200) $PN 271
J 0
(-1990 4210);
DISPLAY 0.617021 (-1990 4210);
PAINT ORANGE (-1990 4210);
FORCEPROP 2 LASTPIN (-2000 4150) $PN 126
J 0
(-1990 4160);
DISPLAY 0.617021 (-1990 4160);
PAINT ORANGE (-1990 4160);
FORCEPROP 2 LASTPIN (-2000 4100) $PN 264
J 0
(-1990 4110);
DISPLAY 0.617021 (-1990 4110);
PAINT ORANGE (-1990 4110);
FORCEPROP 2 LASTPIN (-2000 4050) $PN 119
J 0
(-1990 4060);
DISPLAY 0.617021 (-1990 4060);
PAINT ORANGE (-1990 4060);
FORCEPROP 2 LASTPIN (-2000 4000) $PN 258
J 0
(-1990 4010);
DISPLAY 0.617021 (-1990 4010);
PAINT ORANGE (-1990 4010);
FORCEPROP 2 LASTPIN (-2000 3950) $PN 113
J 0
(-1990 3960);
DISPLAY 0.617021 (-1990 3960);
PAINT ORANGE (-1990 3960);
FORCEPROP 2 LASTPIN (-2000 3900) $PN 251
J 0
(-1990 3910);
DISPLAY 0.617021 (-1990 3910);
PAINT ORANGE (-1990 3910);
FORCEPROP 2 LASTPIN (-2000 3850) $PN 106
J 0
(-1990 3860);
DISPLAY 0.617021 (-1990 3860);
PAINT ORANGE (-1990 3860);
FORCEPROP 2 LASTPIN (-2000 3800) $PN 260
J 0
(-1990 3810);
DISPLAY 0.617021 (-1990 3810);
PAINT ORANGE (-1990 3810);
FORCEPROP 2 LASTPIN (-2000 3750) $PN 115
J 0
(-1990 3760);
DISPLAY 0.617021 (-1990 3760);
PAINT ORANGE (-1990 3760);
FORCEPROP 2 LASTPIN (-2000 3700) $PN 253
J 0
(-1990 3710);
DISPLAY 0.617021 (-1990 3710);
PAINT ORANGE (-1990 3710);
FORCEPROP 2 LASTPIN (-2000 3650) $PN 108
J 0
(-1990 3660);
DISPLAY 0.617021 (-1990 3660);
PAINT ORANGE (-1990 3660);
FORCEPROP 2 LASTPIN (-2000 3600) $PN 247
J 0
(-1990 3610);
DISPLAY 0.617021 (-1990 3610);
PAINT ORANGE (-1990 3610);
FORCEPROP 2 LASTPIN (-2000 3550) $PN 102
J 0
(-1990 3560);
DISPLAY 0.617021 (-1990 3560);
PAINT ORANGE (-1990 3560);
FORCEPROP 2 LASTPIN (-2000 3500) $PN 240
J 0
(-1990 3510);
DISPLAY 0.617021 (-1990 3510);
PAINT ORANGE (-1990 3510);
FORCEPROP 2 LASTPIN (-2000 3450) $PN 95
J 0
(-1990 3460);
DISPLAY 0.617021 (-1990 3460);
PAINT ORANGE (-1990 3460);
FORCEPROP 2 LASTPIN (-2000 3400) $PN 249
J 0
(-1990 3410);
DISPLAY 0.617021 (-1990 3410);
PAINT ORANGE (-1990 3410);
FORCEPROP 2 LASTPIN (-2000 3350) $PN 104
J 0
(-1990 3360);
DISPLAY 0.617021 (-1990 3360);
PAINT ORANGE (-1990 3360);
FORCEPROP 2 LASTPIN (-2000 3300) $PN 242
J 0
(-1990 3310);
DISPLAY 0.617021 (-1990 3310);
PAINT ORANGE (-1990 3310);
FORCEPROP 2 LASTPIN (-2000 3250) $PN 97
J 0
(-1990 3260);
DISPLAY 0.617021 (-1990 3260);
PAINT ORANGE (-1990 3260);
FORCEPROP 2 LASTPIN (-2000 3200) $PN 188
J 0
(-1990 3210);
DISPLAY 0.617021 (-1990 3210);
PAINT ORANGE (-1990 3210);
FORCEPROP 2 LASTPIN (-2000 3150) $PN 43
J 0
(-1990 3160);
DISPLAY 0.617021 (-1990 3160);
PAINT ORANGE (-1990 3160);
FORCEPROP 2 LASTPIN (-2000 3100) $PN 181
J 0
(-1990 3110);
DISPLAY 0.617021 (-1990 3110);
PAINT ORANGE (-1990 3110);
FORCEPROP 2 LASTPIN (-2000 3050) $PN 36
J 0
(-1990 3060);
DISPLAY 0.617021 (-1990 3060);
PAINT ORANGE (-1990 3060);
FORCEPROP 2 LASTPIN (-2000 3000) $PN 190
J 0
(-1990 3010);
DISPLAY 0.617021 (-1990 3010);
PAINT ORANGE (-1990 3010);
FORCEPROP 2 LASTPIN (-2000 2950) $PN 45
J 0
(-1990 2960);
DISPLAY 0.617021 (-1990 2960);
PAINT ORANGE (-1990 2960);
FORCEPROP 2 LASTPIN (-2000 2900) $PN 183
J 0
(-1990 2910);
DISPLAY 0.617021 (-1990 2910);
PAINT ORANGE (-1990 2910);
FORCEPROP 2 LASTPIN (-2000 2850) $PN 38
J 0
(-1990 2860);
DISPLAY 0.617021 (-1990 2860);
PAINT ORANGE (-1990 2860);
FORCEPROP 2 LASTPIN (-2000 2800) $PN 177
J 0
(-1990 2810);
DISPLAY 0.617021 (-1990 2810);
PAINT ORANGE (-1990 2810);
FORCEPROP 2 LASTPIN (-2000 2750) $PN 32
J 0
(-1990 2760);
DISPLAY 0.617021 (-1990 2760);
PAINT ORANGE (-1990 2760);
FORCEPROP 2 LASTPIN (-2000 2700) $PN 170
J 0
(-1990 2710);
DISPLAY 0.617021 (-1990 2710);
PAINT ORANGE (-1990 2710);
FORCEPROP 2 LASTPIN (-2000 2650) $PN 25
J 0
(-1990 2660);
DISPLAY 0.617021 (-1990 2660);
PAINT ORANGE (-1990 2660);
FORCEPROP 2 LASTPIN (-2000 2600) $PN 179
J 0
(-1990 2610);
DISPLAY 0.617021 (-1990 2610);
PAINT ORANGE (-1990 2610);
FORCEPROP 2 LASTPIN (-2000 2550) $PN 34
J 0
(-1990 2560);
DISPLAY 0.617021 (-1990 2560);
PAINT ORANGE (-1990 2560);
FORCEPROP 2 LASTPIN (-2000 2500) $PN 172
J 0
(-1990 2510);
DISPLAY 0.617021 (-1990 2510);
PAINT ORANGE (-1990 2510);
FORCEPROP 2 LASTPIN (-2000 2450) $PN 27
J 0
(-1990 2460);
DISPLAY 0.617021 (-1990 2460);
PAINT ORANGE (-1990 2460);
FORCEPROP 2 LASTPIN (-2000 2400) $PN 166
J 0
(-1990 2410);
DISPLAY 0.617021 (-1990 2410);
PAINT ORANGE (-1990 2410);
FORCEPROP 2 LASTPIN (-2000 2350) $PN 21
J 0
(-1990 2360);
DISPLAY 0.617021 (-1990 2360);
PAINT ORANGE (-1990 2360);
FORCEPROP 2 LASTPIN (-2000 2300) $PN 159
J 0
(-1990 2310);
DISPLAY 0.617021 (-1990 2310);
PAINT ORANGE (-1990 2310);
FORCEPROP 2 LASTPIN (-2000 2250) $PN 14
J 0
(-1990 2260);
DISPLAY 0.617021 (-1990 2260);
PAINT ORANGE (-1990 2260);
FORCEPROP 2 LASTPIN (-2000 2200) $PN 168
J 0
(-1990 2210);
DISPLAY 0.617021 (-1990 2210);
PAINT ORANGE (-1990 2210);
FORCEPROP 2 LASTPIN (-2000 2150) $PN 23
J 0
(-1990 2160);
DISPLAY 0.617021 (-1990 2160);
PAINT ORANGE (-1990 2160);
FORCEPROP 2 LASTPIN (-2000 2100) $PN 161
J 0
(-1990 2110);
DISPLAY 0.617021 (-1990 2110);
PAINT ORANGE (-1990 2110);
FORCEPROP 2 LASTPIN (-2000 2050) $PN 16
J 0
(-1990 2060);
DISPLAY 0.617021 (-1990 2060);
PAINT ORANGE (-1990 2060);
FORCEPROP 2 LASTPIN (-2000 2000) $PN 155
J 0
(-1990 2010);
DISPLAY 0.617021 (-1990 2010);
PAINT ORANGE (-1990 2010);
FORCEPROP 2 LASTPIN (-2000 1950) $PN 10
J 0
(-1990 1960);
DISPLAY 0.617021 (-1990 1960);
PAINT ORANGE (-1990 1960);
FORCEPROP 2 LASTPIN (-2000 1900) $PN 148
J 0
(-1990 1910);
DISPLAY 0.617021 (-1990 1910);
PAINT ORANGE (-1990 1910);
FORCEPROP 2 LASTPIN (-2000 1850) $PN 3
J 0
(-1990 1860);
DISPLAY 0.617021 (-1990 1860);
PAINT ORANGE (-1990 1860);
FORCEPROP 2 LASTPIN (-2000 1800) $PN 157
J 0
(-1990 1810);
DISPLAY 0.617021 (-1990 1810);
PAINT ORANGE (-1990 1810);
FORCEPROP 2 LASTPIN (-2000 1750) $PN 12
J 0
(-1990 1760);
DISPLAY 0.617021 (-1990 1760);
PAINT ORANGE (-1990 1760);
FORCEPROP 2 LASTPIN (-2000 1700) $PN 150
J 0
(-1990 1710);
DISPLAY 0.617021 (-1990 1710);
PAINT ORANGE (-1990 1710);
FORCEPROP 2 LASTPIN (-2000 1650) $PN 5
J 0
(-1990 1660);
DISPLAY 0.617021 (-1990 1660);
PAINT ORANGE (-1990 1660);
FORCEPROP 2 LASTPIN (-3000 3050) $PN 203
J 2
(-3010 3060);
DISPLAY 0.617021 (-3010 3060);
PAINT ORANGE (-3010 3060);
FORCEPROP 2 LASTPIN (-3000 3000) $PN 60
J 2
(-3010 3010);
DISPLAY 0.617021 (-3010 3010);
PAINT ORANGE (-3010 3010);
FORCEPROP 2 LASTPIN (-3000 3600) $PN 218
J 2
(-3010 3610);
DISPLAY 0.617021 (-3010 3610);
PAINT ORANGE (-3010 3610);
FORCEPROP 2 LASTPIN (-3000 3550) $PN 219
J 2
(-3010 3560);
DISPLAY 0.617021 (-3010 3560);
PAINT ORANGE (-3010 3560);
FORCEPROP 2 LASTPIN (-3000 3500) $PN 74
J 2
(-3010 3510);
DISPLAY 0.617021 (-3010 3510);
PAINT ORANGE (-3010 3510);
FORCEPROP 2 LASTPIN (-3000 3450) $PN 75
J 2
(-3010 3460);
DISPLAY 0.617021 (-3010 3460);
PAINT ORANGE (-3010 3460);
FORCEPROP 2 LASTPIN (-3000 2750) $PN 199
J 2
(-3010 2760);
DISPLAY 0.617021 (-3010 2760);
PAINT ORANGE (-3010 2760);
FORCEPROP 2 LASTPIN (-3000 2700) $PN 54
J 2
(-3010 2710);
DISPLAY 0.617021 (-3010 2710);
PAINT ORANGE (-3010 2710);
FORCEPROP 2 LASTPIN (-3000 2650) $PN 192
J 2
(-3010 2660);
DISPLAY 0.617021 (-3010 2660);
PAINT ORANGE (-3010 2660);
FORCEPROP 2 LASTPIN (-3000 2600) $PN 47
J 2
(-3010 2610);
DISPLAY 0.617021 (-3010 2610);
PAINT ORANGE (-3010 2610);
FORCEPROP 2 LASTPIN (-3000 2550) $PN 201
J 2
(-3010 2560);
DISPLAY 0.617021 (-3010 2560);
PAINT ORANGE (-3010 2560);
FORCEPROP 2 LASTPIN (-3000 2500) $PN 56
J 2
(-3010 2510);
DISPLAY 0.617021 (-3010 2510);
PAINT ORANGE (-3010 2510);
FORCEPROP 2 LASTPIN (-3000 2450) $PN 194
J 2
(-3010 2460);
DISPLAY 0.617021 (-3010 2460);
PAINT ORANGE (-3010 2460);
FORCEPROP 2 LASTPIN (-3000 2400) $PN 49
J 2
(-3010 2410);
DISPLAY 0.617021 (-3010 2410);
PAINT ORANGE (-3010 2410);
FORCEPROP 2 LASTPIN (-3000 3350) $PN 235
J 2
(-3010 3360);
DISPLAY 0.617021 (-3010 3360);
PAINT ORANGE (-3010 3360);
FORCEPROP 2 LASTPIN (-3000 3750) $PN 207
J 2
(-3010 3760);
DISPLAY 0.617021 (-3010 3760);
PAINT ORANGE (-3010 3760);
FORCEPROP 2 LASTPIN (-3000 3700) $PN 63
J 2
(-3010 3710);
DISPLAY 0.617021 (-3010 3710);
PAINT ORANGE (-3010 3710);
FORCEPROP 2 LASTPIN (-3000 3850) $PN 224
J 2
(-3010 3860);
DISPLAY 0.617021 (-3010 3860);
PAINT ORANGE (-3010 3860);
FORCEPROP 2 LASTPIN (-3000 3800) $PN 81
J 2
(-3010 3810);
DISPLAY 0.617021 (-3010 3810);
PAINT ORANGE (-3010 3810);
FORCEPROP 2 LASTPIN (-3000 2150) $PN 208
J 2
(-3010 2160);
DISPLAY 0.617021 (-3010 2160);
PAINT ORANGE (-3010 2160);
FORCEPROP 2 LASTPIN (-3000 2100) $PN 62
J 2
(-3010 2110);
DISPLAY 0.617021 (-3010 2110);
PAINT ORANGE (-3010 2110);
FORCEPROP 2 LASTPIN (-3000 4800) $PN 234
J 2
(-3010 4810);
DISPLAY 0.617021 (-3010 4810);
PAINT ORANGE (-3010 4810);
FORCEPROP 2 LASTPIN (-3000 4750) $PN 82
J 2
(-3010 4760);
DISPLAY 0.617021 (-3010 4760);
PAINT ORANGE (-3010 4760);
FORCEPROP 2 LASTPIN (-3000 4700) $PN 86
J 2
(-3010 4710);
DISPLAY 0.617021 (-3010 4710);
PAINT ORANGE (-3010 4710);
FORCEPROP 2 LASTPIN (-3000 4650) $PN 228
J 2
(-3010 4660);
DISPLAY 0.617021 (-3010 4660);
PAINT ORANGE (-3010 4660);
FORCEPROP 2 LASTPIN (-3000 4600) $PN 232
J 2
(-3010 4610);
DISPLAY 0.617021 (-3010 4610);
PAINT ORANGE (-3010 4610);
FORCEPROP 2 LASTPIN (-3000 4550) $PN 65
J 2
(-3010 4560);
DISPLAY 0.617021 (-3010 4560);
PAINT ORANGE (-3010 4560);
FORCEPROP 2 LASTPIN (-3000 4500) $PN 210
J 2
(-3010 4510);
DISPLAY 0.617021 (-3010 4510);
PAINT ORANGE (-3010 4510);
FORCEPROP 2 LASTPIN (-3000 4450) $PN 225
J 2
(-3010 4460);
DISPLAY 0.617021 (-3010 4460);
PAINT ORANGE (-3010 4460);
FORCEPROP 2 LASTPIN (-3000 4400) $PN 66
J 2
(-3010 4410);
DISPLAY 0.617021 (-3010 4410);
PAINT ORANGE (-3010 4410);
FORCEPROP 2 LASTPIN (-3000 4350) $PN 68
J 2
(-3010 4360);
DISPLAY 0.617021 (-3010 4360);
PAINT ORANGE (-3010 4360);
FORCEPROP 2 LASTPIN (-3000 4300) $PN 211
J 2
(-3010 4310);
DISPLAY 0.617021 (-3010 4310);
PAINT ORANGE (-3010 4310);
FORCEPROP 2 LASTPIN (-3000 4250) $PN 69
J 2
(-3010 4260);
DISPLAY 0.617021 (-3010 4260);
PAINT ORANGE (-3010 4260);
FORCEPROP 2 LASTPIN (-3000 4200) $PN 213
J 2
(-3010 4210);
DISPLAY 0.617021 (-3010 4210);
PAINT ORANGE (-3010 4210);
FORCEPROP 2 LASTPIN (-3000 4150) $PN 214
J 2
(-3010 4160);
DISPLAY 0.617021 (-3010 4160);
PAINT ORANGE (-3010 4160);
FORCEPROP 2 LASTPIN (-3000 4100) $PN 71
J 2
(-3010 4110);
DISPLAY 0.617021 (-3010 4110);
PAINT ORANGE (-3010 4110);
FORCEPROP 2 LASTPIN (-3000 4050) $PN 216
J 2
(-3010 4060);
DISPLAY 0.617021 (-3010 4060);
PAINT ORANGE (-3010 4060);
FORCEPROP 2 LASTPIN (-3000 4000) $PN 72
J 2
(-3010 4010);
DISPLAY 0.617021 (-3010 4010);
PAINT ORANGE (-3010 4010);
FORCEPROP 2 LASTPIN (-3000 3950) $PN 79
J 2
(-3010 3960);
DISPLAY 0.617021 (-3010 3960);
PAINT ORANGE (-3010 3960);
FORCEPROP 1 LAST PACK_TYPE PIP
J 0
(-2950 5100);
PAINT SKYBLUE (-2950 5100);
DISPLAY INVISIBLE (-2950 5100);
FORCEPROP 2 LAST BOM_COST MEM
J 0
(-2500 3150);
PAINT ORANGE (-2500 3150);
DISPLAY INVISIBLE (-2500 3150);
FORCEPROP 2 LAST CDS_LIB mstr_sconn
J 0
(-2500 3150);
PAINT ORANGE (-2500 3150);
DISPLAY INVISIBLE (-2500 3150);
FORCEPROP 2 LAST SEC_TYPE PIP
J 0
(-2950 5100);
DISPLAY 1.021277 (-2950 5100);
PAINT ORANGE (-2950 5100);
DISPLAY INVISIBLE (-2950 5100);
FORCEPROP 2 LAST SEC 1
J 0
(-2950 5100);
DISPLAY 0.680851 (-2950 5100);
PAINT MONO (-2950 5100);
DISPLAY INVISIBLE (-2950 5100);
FORCEPROP 2 LAST CDS_LOCATION J9U2
J 0
(-2950 5050);
DISPLAY 0.617021 (-2950 5050);
PAINT AQUA (-2950 5050);
DISPLAY INVISIBLE (-2950 5050);
FORCEPROP 1 LAST PATH I187
J 0
(-2500 5000);
PAINT GREEN (-2500 5000);
DISPLAY INVISIBLE (-2500 5000);
FORCEPROP 2 LAST ROOM DDR4_CH_J
J 0
(-2500 3150);
PAINT ORANGE (-2500 3150);
DISPLAY INVISIBLE (-2500 3150);
FORCEADD SCONN288_H44441003..3
(1750 2350);
FORCEPROP 1 LAST LOCATION J9U2
J 0
(1300 3750);
DISPLAY 0.617021 (1300 3750);
PAINT AQUA (1300 3750);
FORCEPROP 1 LAST PART_NUMBER H44441-003
J 0
(1300 1000);
DISPLAY 0.617021 (1300 1000);
PAINT BLUE (1300 1000);
FORCEPROP 1 LAST MATERIAL SCONN
J 0
(1300 3700);
DISPLAY 0.617021 (1300 3700);
PAINT SKYBLUE (1300 3700);
FORCEPROP 2 LASTPIN (1250 3500) $PN 2
J 2
(1240 3510);
DISPLAY 0.617021 (1240 3510);
PAINT ORANGE (1240 3510);
FORCEPROP 2 LASTPIN (1250 3450) $PN 4
J 2
(1240 3460);
DISPLAY 0.617021 (1240 3460);
PAINT ORANGE (1240 3460);
FORCEPROP 2 LASTPIN (1250 3400) $PN 6
J 2
(1240 3410);
DISPLAY 0.617021 (1240 3410);
PAINT ORANGE (1240 3410);
FORCEPROP 2 LASTPIN (1250 3350) $PN 9
J 2
(1240 3360);
DISPLAY 0.617021 (1240 3360);
PAINT ORANGE (1240 3360);
FORCEPROP 2 LASTPIN (1250 3300) $PN 11
J 2
(1240 3310);
DISPLAY 0.617021 (1240 3310);
PAINT ORANGE (1240 3310);
FORCEPROP 2 LASTPIN (1250 3250) $PN 13
J 2
(1240 3260);
DISPLAY 0.617021 (1240 3260);
PAINT ORANGE (1240 3260);
FORCEPROP 2 LASTPIN (1250 3200) $PN 15
J 2
(1240 3210);
DISPLAY 0.617021 (1240 3210);
PAINT ORANGE (1240 3210);
FORCEPROP 2 LASTPIN (1250 3150) $PN 17
J 2
(1240 3160);
DISPLAY 0.617021 (1240 3160);
PAINT ORANGE (1240 3160);
FORCEPROP 2 LASTPIN (1250 3100) $PN 20
J 2
(1240 3110);
DISPLAY 0.617021 (1240 3110);
PAINT ORANGE (1240 3110);
FORCEPROP 2 LASTPIN (1250 3050) $PN 22
J 2
(1240 3060);
DISPLAY 0.617021 (1240 3060);
PAINT ORANGE (1240 3060);
FORCEPROP 2 LASTPIN (1250 3000) $PN 24
J 2
(1240 3010);
DISPLAY 0.617021 (1240 3010);
PAINT ORANGE (1240 3010);
FORCEPROP 2 LASTPIN (1250 2950) $PN 26
J 2
(1240 2960);
DISPLAY 0.617021 (1240 2960);
PAINT ORANGE (1240 2960);
FORCEPROP 2 LASTPIN (1250 2900) $PN 28
J 2
(1240 2910);
DISPLAY 0.617021 (1240 2910);
PAINT ORANGE (1240 2910);
FORCEPROP 2 LASTPIN (1250 2850) $PN 31
J 2
(1240 2860);
DISPLAY 0.617021 (1240 2860);
PAINT ORANGE (1240 2860);
FORCEPROP 2 LASTPIN (1250 2800) $PN 33
J 2
(1240 2810);
DISPLAY 0.617021 (1240 2810);
PAINT ORANGE (1240 2810);
FORCEPROP 2 LASTPIN (1250 2750) $PN 35
J 2
(1240 2760);
DISPLAY 0.617021 (1240 2760);
PAINT ORANGE (1240 2760);
FORCEPROP 2 LASTPIN (1250 2700) $PN 37
J 2
(1240 2710);
DISPLAY 0.617021 (1240 2710);
PAINT ORANGE (1240 2710);
FORCEPROP 2 LASTPIN (1250 2650) $PN 39
J 2
(1240 2660);
DISPLAY 0.617021 (1240 2660);
PAINT ORANGE (1240 2660);
FORCEPROP 2 LASTPIN (1250 2600) $PN 42
J 2
(1240 2610);
DISPLAY 0.617021 (1240 2610);
PAINT ORANGE (1240 2610);
FORCEPROP 2 LASTPIN (1250 2550) $PN 44
J 2
(1240 2560);
DISPLAY 0.617021 (1240 2560);
PAINT ORANGE (1240 2560);
FORCEPROP 2 LASTPIN (1250 2500) $PN 46
J 2
(1240 2510);
DISPLAY 0.617021 (1240 2510);
PAINT ORANGE (1240 2510);
FORCEPROP 2 LASTPIN (1250 2450) $PN 48
J 2
(1240 2460);
DISPLAY 0.617021 (1240 2460);
PAINT ORANGE (1240 2460);
FORCEPROP 2 LASTPIN (1250 2400) $PN 50
J 2
(1240 2410);
DISPLAY 0.617021 (1240 2410);
PAINT ORANGE (1240 2410);
FORCEPROP 2 LASTPIN (1250 2350) $PN 53
J 2
(1240 2360);
DISPLAY 0.617021 (1240 2360);
PAINT ORANGE (1240 2360);
FORCEPROP 2 LASTPIN (1250 2300) $PN 55
J 2
(1240 2310);
DISPLAY 0.617021 (1240 2310);
PAINT ORANGE (1240 2310);
FORCEPROP 2 LASTPIN (1250 2250) $PN 57
J 2
(1240 2260);
DISPLAY 0.617021 (1240 2260);
PAINT ORANGE (1240 2260);
FORCEPROP 2 LASTPIN (1250 2200) $PN 94
J 2
(1240 2210);
DISPLAY 0.617021 (1240 2210);
PAINT ORANGE (1240 2210);
FORCEPROP 2 LASTPIN (1250 2150) $PN 96
J 2
(1240 2160);
DISPLAY 0.617021 (1240 2160);
PAINT ORANGE (1240 2160);
FORCEPROP 2 LASTPIN (1250 2100) $PN 98
J 2
(1240 2110);
DISPLAY 0.617021 (1240 2110);
PAINT ORANGE (1240 2110);
FORCEPROP 2 LASTPIN (1250 2050) $PN 101
J 2
(1240 2060);
DISPLAY 0.617021 (1240 2060);
PAINT ORANGE (1240 2060);
FORCEPROP 2 LASTPIN (1250 2000) $PN 103
J 2
(1240 2010);
DISPLAY 0.617021 (1240 2010);
PAINT ORANGE (1240 2010);
FORCEPROP 2 LASTPIN (1250 1950) $PN 105
J 2
(1240 1960);
DISPLAY 0.617021 (1240 1960);
PAINT ORANGE (1240 1960);
FORCEPROP 2 LASTPIN (1250 1900) $PN 107
J 2
(1240 1910);
DISPLAY 0.617021 (1240 1910);
PAINT ORANGE (1240 1910);
FORCEPROP 2 LASTPIN (1250 1850) $PN 109
J 2
(1240 1860);
DISPLAY 0.617021 (1240 1860);
PAINT ORANGE (1240 1860);
FORCEPROP 2 LASTPIN (1250 1800) $PN 112
J 2
(1240 1810);
DISPLAY 0.617021 (1240 1810);
PAINT ORANGE (1240 1810);
FORCEPROP 2 LASTPIN (1250 1750) $PN 114
J 2
(1240 1760);
DISPLAY 0.617021 (1240 1760);
PAINT ORANGE (1240 1760);
FORCEPROP 2 LASTPIN (1250 1700) $PN 116
J 2
(1240 1710);
DISPLAY 0.617021 (1240 1710);
PAINT ORANGE (1240 1710);
FORCEPROP 2 LASTPIN (1250 1650) $PN 118
J 2
(1240 1660);
DISPLAY 0.617021 (1240 1660);
PAINT ORANGE (1240 1660);
FORCEPROP 2 LASTPIN (1250 1600) $PN 120
J 2
(1240 1610);
DISPLAY 0.617021 (1240 1610);
PAINT ORANGE (1240 1610);
FORCEPROP 2 LASTPIN (1250 1550) $PN 123
J 2
(1240 1560);
DISPLAY 0.617021 (1240 1560);
PAINT ORANGE (1240 1560);
FORCEPROP 2 LASTPIN (1250 1500) $PN 125
J 2
(1240 1510);
DISPLAY 0.617021 (1240 1510);
PAINT ORANGE (1240 1510);
FORCEPROP 2 LASTPIN (1250 1450) $PN 127
J 2
(1240 1460);
DISPLAY 0.617021 (1240 1460);
PAINT ORANGE (1240 1460);
FORCEPROP 2 LASTPIN (1250 1400) $PN 129
J 2
(1240 1410);
DISPLAY 0.617021 (1240 1410);
PAINT ORANGE (1240 1410);
FORCEPROP 2 LASTPIN (1250 1350) $PN 131
J 2
(1240 1360);
DISPLAY 0.617021 (1240 1360);
PAINT ORANGE (1240 1360);
FORCEPROP 2 LASTPIN (1250 1300) $PN 134
J 2
(1240 1310);
DISPLAY 0.617021 (1240 1310);
PAINT ORANGE (1240 1310);
FORCEPROP 2 LASTPIN (1250 1250) $PN 136
J 2
(1240 1260);
DISPLAY 0.617021 (1240 1260);
PAINT ORANGE (1240 1260);
FORCEPROP 2 LASTPIN (1250 1200) $PN 138
J 2
(1240 1210);
DISPLAY 0.617021 (1240 1210);
PAINT ORANGE (1240 1210);
FORCEPROP 2 LASTPIN (2250 3500) $PN 147
J 0
(2260 3510);
DISPLAY 0.617021 (2260 3510);
PAINT ORANGE (2260 3510);
FORCEPROP 2 LASTPIN (2250 3450) $PN 149
J 0
(2260 3460);
DISPLAY 0.617021 (2260 3460);
PAINT ORANGE (2260 3460);
FORCEPROP 2 LASTPIN (2250 3400) $PN 151
J 0
(2260 3410);
DISPLAY 0.617021 (2260 3410);
PAINT ORANGE (2260 3410);
FORCEPROP 2 LASTPIN (2250 3350) $PN 154
J 0
(2260 3360);
DISPLAY 0.617021 (2260 3360);
PAINT ORANGE (2260 3360);
FORCEPROP 2 LASTPIN (2250 3300) $PN 156
J 0
(2260 3310);
DISPLAY 0.617021 (2260 3310);
PAINT ORANGE (2260 3310);
FORCEPROP 2 LASTPIN (2250 3250) $PN 158
J 0
(2260 3260);
DISPLAY 0.617021 (2260 3260);
PAINT ORANGE (2260 3260);
FORCEPROP 2 LASTPIN (2250 3200) $PN 160
J 0
(2260 3210);
DISPLAY 0.617021 (2260 3210);
PAINT ORANGE (2260 3210);
FORCEPROP 2 LASTPIN (2250 3150) $PN 162
J 0
(2260 3160);
DISPLAY 0.617021 (2260 3160);
PAINT ORANGE (2260 3160);
FORCEPROP 2 LASTPIN (2250 3100) $PN 165
J 0
(2260 3110);
DISPLAY 0.617021 (2260 3110);
PAINT ORANGE (2260 3110);
FORCEPROP 2 LASTPIN (2250 3050) $PN 167
J 0
(2260 3060);
DISPLAY 0.617021 (2260 3060);
PAINT ORANGE (2260 3060);
FORCEPROP 2 LASTPIN (2250 3000) $PN 169
J 0
(2260 3010);
DISPLAY 0.617021 (2260 3010);
PAINT ORANGE (2260 3010);
FORCEPROP 2 LASTPIN (2250 2950) $PN 171
J 0
(2260 2960);
DISPLAY 0.617021 (2260 2960);
PAINT ORANGE (2260 2960);
FORCEPROP 2 LASTPIN (2250 2900) $PN 173
J 0
(2260 2910);
DISPLAY 0.617021 (2260 2910);
PAINT ORANGE (2260 2910);
FORCEPROP 2 LASTPIN (2250 2850) $PN 176
J 0
(2260 2860);
DISPLAY 0.617021 (2260 2860);
PAINT ORANGE (2260 2860);
FORCEPROP 2 LASTPIN (2250 2800) $PN 178
J 0
(2260 2810);
DISPLAY 0.617021 (2260 2810);
PAINT ORANGE (2260 2810);
FORCEPROP 2 LASTPIN (2250 2750) $PN 180
J 0
(2260 2760);
DISPLAY 0.617021 (2260 2760);
PAINT ORANGE (2260 2760);
FORCEPROP 2 LASTPIN (2250 2700) $PN 182
J 0
(2260 2710);
DISPLAY 0.617021 (2260 2710);
PAINT ORANGE (2260 2710);
FORCEPROP 2 LASTPIN (2250 2650) $PN 184
J 0
(2260 2660);
DISPLAY 0.617021 (2260 2660);
PAINT ORANGE (2260 2660);
FORCEPROP 2 LASTPIN (2250 2600) $PN 187
J 0
(2260 2610);
DISPLAY 0.617021 (2260 2610);
PAINT ORANGE (2260 2610);
FORCEPROP 2 LASTPIN (2250 2550) $PN 189
J 0
(2260 2560);
DISPLAY 0.617021 (2260 2560);
PAINT ORANGE (2260 2560);
FORCEPROP 2 LASTPIN (2250 2500) $PN 191
J 0
(2260 2510);
DISPLAY 0.617021 (2260 2510);
PAINT ORANGE (2260 2510);
FORCEPROP 2 LASTPIN (2250 2450) $PN 193
J 0
(2260 2460);
DISPLAY 0.617021 (2260 2460);
PAINT ORANGE (2260 2460);
FORCEPROP 2 LASTPIN (2250 2400) $PN 195
J 0
(2260 2410);
DISPLAY 0.617021 (2260 2410);
PAINT ORANGE (2260 2410);
FORCEPROP 2 LASTPIN (2250 2350) $PN 198
J 0
(2260 2360);
DISPLAY 0.617021 (2260 2360);
PAINT ORANGE (2260 2360);
FORCEPROP 2 LASTPIN (2250 2300) $PN 200
J 0
(2260 2310);
DISPLAY 0.617021 (2260 2310);
PAINT ORANGE (2260 2310);
FORCEPROP 2 LASTPIN (2250 2250) $PN 202
J 0
(2260 2260);
DISPLAY 0.617021 (2260 2260);
PAINT ORANGE (2260 2260);
FORCEPROP 2 LASTPIN (2250 2200) $PN 239
J 0
(2260 2210);
DISPLAY 0.617021 (2260 2210);
PAINT ORANGE (2260 2210);
FORCEPROP 2 LASTPIN (2250 2150) $PN 241
J 0
(2260 2160);
DISPLAY 0.617021 (2260 2160);
PAINT ORANGE (2260 2160);
FORCEPROP 2 LASTPIN (2250 2100) $PN 243
J 0
(2260 2110);
DISPLAY 0.617021 (2260 2110);
PAINT ORANGE (2260 2110);
FORCEPROP 2 LASTPIN (2250 2050) $PN 246
J 0
(2260 2060);
DISPLAY 0.617021 (2260 2060);
PAINT ORANGE (2260 2060);
FORCEPROP 2 LASTPIN (2250 2000) $PN 248
J 0
(2260 2010);
DISPLAY 0.617021 (2260 2010);
PAINT ORANGE (2260 2010);
FORCEPROP 2 LASTPIN (2250 1950) $PN 250
J 0
(2260 1960);
DISPLAY 0.617021 (2260 1960);
PAINT ORANGE (2260 1960);
FORCEPROP 2 LASTPIN (2250 1900) $PN 252
J 0
(2260 1910);
DISPLAY 0.617021 (2260 1910);
PAINT ORANGE (2260 1910);
FORCEPROP 2 LASTPIN (2250 1850) $PN 254
J 0
(2260 1860);
DISPLAY 0.617021 (2260 1860);
PAINT ORANGE (2260 1860);
FORCEPROP 2 LASTPIN (2250 1800) $PN 257
J 0
(2260 1810);
DISPLAY 0.617021 (2260 1810);
PAINT ORANGE (2260 1810);
FORCEPROP 2 LASTPIN (2250 1750) $PN 259
J 0
(2260 1760);
DISPLAY 0.617021 (2260 1760);
PAINT ORANGE (2260 1760);
FORCEPROP 2 LASTPIN (2250 1700) $PN 261
J 0
(2260 1710);
DISPLAY 0.617021 (2260 1710);
PAINT ORANGE (2260 1710);
FORCEPROP 2 LASTPIN (2250 1650) $PN 263
J 0
(2260 1660);
DISPLAY 0.617021 (2260 1660);
PAINT ORANGE (2260 1660);
FORCEPROP 2 LASTPIN (2250 1600) $PN 265
J 0
(2260 1610);
DISPLAY 0.617021 (2260 1610);
PAINT ORANGE (2260 1610);
FORCEPROP 2 LASTPIN (2250 1550) $PN 268
J 0
(2260 1560);
DISPLAY 0.617021 (2260 1560);
PAINT ORANGE (2260 1560);
FORCEPROP 2 LASTPIN (2250 1500) $PN 270
J 0
(2260 1510);
DISPLAY 0.617021 (2260 1510);
PAINT ORANGE (2260 1510);
FORCEPROP 2 LASTPIN (2250 1450) $PN 272
J 0
(2260 1460);
DISPLAY 0.617021 (2260 1460);
PAINT ORANGE (2260 1460);
FORCEPROP 2 LASTPIN (2250 1400) $PN 274
J 0
(2260 1410);
DISPLAY 0.617021 (2260 1410);
PAINT ORANGE (2260 1410);
FORCEPROP 2 LASTPIN (2250 1350) $PN 276
J 0
(2260 1360);
DISPLAY 0.617021 (2260 1360);
PAINT ORANGE (2260 1360);
FORCEPROP 2 LASTPIN (2250 1300) $PN 279
J 0
(2260 1310);
DISPLAY 0.617021 (2260 1310);
PAINT ORANGE (2260 1310);
FORCEPROP 2 LASTPIN (2250 1250) $PN 281
J 0
(2260 1260);
DISPLAY 0.617021 (2260 1260);
PAINT ORANGE (2260 1260);
FORCEPROP 2 LASTPIN (2250 1200) $PN 283
J 0
(2260 1210);
DISPLAY 0.617021 (2260 1210);
PAINT ORANGE (2260 1210);
FORCEPROP 1 LAST PACK_TYPE PIP
J 0
(1300 3800);
PAINT SKYBLUE (1300 3800);
DISPLAY INVISIBLE (1300 3800);
FORCEPROP 2 LAST BOM_COST MEM
J 0
(1750 2350);
PAINT ORANGE (1750 2350);
DISPLAY INVISIBLE (1750 2350);
FORCEPROP 2 LAST CDS_LIB mstr_sconn
J 0
(1750 2350);
PAINT ORANGE (1750 2350);
DISPLAY INVISIBLE (1750 2350);
FORCEPROP 2 LAST SEC_TYPE PIP
J 0
(1300 3800);
DISPLAY 1.021277 (1300 3800);
PAINT ORANGE (1300 3800);
DISPLAY INVISIBLE (1300 3800);
FORCEPROP 2 LAST SEC 3
J 0
(1300 3800);
DISPLAY 0.680851 (1300 3800);
PAINT MONO (1300 3800);
DISPLAY INVISIBLE (1300 3800);
FORCEPROP 2 LAST CDS_LOCATION J9U2
J 0
(1300 3750);
DISPLAY 0.617021 (1300 3750);
PAINT AQUA (1300 3750);
DISPLAY INVISIBLE (1300 3750);
FORCEPROP 1 LAST PATH I188
J 0
(1750 3700);
PAINT GREEN (1750 3700);
DISPLAY INVISIBLE (1750 3700);
FORCEPROP 2 LAST ROOM DDR4_CH_J
J 0
(1750 2350);
PAINT ORANGE (1750 2350);
DISPLAY INVISIBLE (1750 2350);
FORCEADD GND..1
(-5200 1800);
FORCEPROP 3 LASTPIN (-5200 1850) SIG_NAME GND\g
J 0
(-5190 1860);
DISPLAY 0.659574 (-5190 1860);
PAINT MONO (-5190 1860);
DISPLAY INVISIBLE (-5190 1860);
FORCEPROP 1 LAST VOLTAGE 0
J 0
(-5200 1800);
PAINT SKYBLUE (-5200 1800);
DISPLAY INVISIBLE (-5200 1800);
FORCEPROP 2 LAST BOM_COST MEM
J 0
(-5200 1805);
PAINT ORANGE (-5200 1805);
DISPLAY INVISIBLE (-5200 1805);
FORCEPROP 1 LAST SIZE 1B
J 0
(-5125 1750);
DISPLAY 1.787234 (-5125 1750);
PAINT GREEN (-5125 1750);
DISPLAY INVISIBLE (-5125 1750);
FORCEPROP 2 LAST CDS_LIB mstr_symbols
J 0
(-5200 1800);
PAINT ORANGE (-5200 1800);
DISPLAY INVISIBLE (-5200 1800);
FORCEPROP 1 LAST BODY_TYPE PLUMBING
J 0
(-5245 1757);
DISPLAY 0.340426 (-5245 1757);
PAINT GREEN (-5245 1757);
DISPLAY INVISIBLE (-5245 1757);
FORCEPROP 1 LAST PATH I189
J 0
(-5125 1800);
DISPLAY 0.872340 (-5125 1800);
PAINT AQUA (-5125 1800);
DISPLAY INVISIBLE (-5125 1800);
FORCEPROP 2 LAST ROOM DDR4_CH_J
J 0
(-5200 1805);
PAINT ORANGE (-5200 1805);
DISPLAY INVISIBLE (-5200 1805);
FORCEPROP 1 LAST HDL_POWER GND
J 0
(-5200 1950);
DISPLAY 1.404255 (-5200 1950);
PAINT GREEN (-5200 1950);
DISPLAY INVISIBLE (-5200 1950);
FORCEADD TAP..6
R 2
(850 4400);
FORCEPROP 3 LASTPIN (800 4400) SIG_NAME M_J_DQS_DN<10>
J 0
(810 4410);
DISPLAY 0.659574 (810 4410);
PAINT MONO (810 4410);
DISPLAY INVISIBLE (810 4410);
FORCEPROP 1 LASTPIN (800 4400) BN 10
J 2
(850 4410);
DISPLAY 0.617021 (850 4410);
PAINT PINK (850 4410);
FORCEPROP 2 LAST CDS_LIB mstr_standard
J 0
(850 4400);
DISPLAY 0.787234 (850 4400);
PAINT MONO (850 4400);
DISPLAY INVISIBLE (850 4400);
FORCEPROP 1 LAST BODY_TYPE PLUMBING
J 2
(850 4350);
DISPLAY 1.234043 (850 4350);
PAINT GREEN (850 4350);
DISPLAY INVISIBLE (850 4350);
FORCEPROP 1 LAST HDL_TAP TRUE
J 2
(525 4275);
DISPLAY 1.234043 (525 4275);
PAINT GREEN (525 4275);
DISPLAY INVISIBLE (525 4275);
FORCEPROP 1 LAST PATH I19
J 2
(850 4400);
DISPLAY 0.936170 (850 4400);
PAINT GREEN (850 4400);
DISPLAY INVISIBLE (850 4400);
FORCEADD P12V_NVDIMM_GHJ..1
(350 3025);
FORCEPROP 3 LASTPIN (350 2975) SIG_NAME P12V_NVDIMM_GHJ\g
J 0
(360 2985);
DISPLAY 0.659574 (360 2985);
PAINT MONO (360 2985);
DISPLAY INVISIBLE (360 2985);
FORCEPROP 1 LAST VOLTAGE 12.0
J 0
(305 2982);
DISPLAY 0.340426 (305 2982);
PAINT SKYBLUE (305 2982);
DISPLAY INVISIBLE (305 2982);
FORCEPROP 2 LAST CDS_LIB mstr_symbols
J 0
(350 3025);
PAINT ORANGE (350 3025);
DISPLAY INVISIBLE (350 3025);
FORCEPROP 1 LAST BODY_TYPE PLUMBING
J 0
(305 2982);
DISPLAY 0.340426 (305 2982);
PAINT GREEN (305 2982);
DISPLAY INVISIBLE (305 2982);
FORCEPROP 1 LAST PATH I190
J 0
(400 3050);
DISPLAY 0.872340 (400 3050);
PAINT AQUA (400 3050);
DISPLAY INVISIBLE (400 3050);
FORCEPROP 1 LAST HDL_POWER P12V_NVDIMM_GHJ
J 1
(350 3075);
DISPLAY 0.872340 (350 3075);
PAINT GREEN (350 3075);
DISPLAY INVISIBLE (350 3075);
FORCEADD OFFPAGE..3
(1550 5200);
FORCEPROP 2 LAST $XR0 59 
J 0
(1764 5200);
DISPLAY 0.638298 (1764 5200);
PAINT MONO (1764 5200);
FORCEPROP 2 LAST $XR1 81 
J 0
(1854 5200);
DISPLAY 0.638298 (1854 5200);
PAINT MONO (1854 5200);
FORCEPROP 2 LAST CDS_LIB mstr_standard
J 0
(1550 5200);
DISPLAY 0.787234 (1550 5200);
PAINT MONO (1550 5200);
DISPLAY INVISIBLE (1550 5200);
FORCEPROP 1 LAST OFFPAGE TRUE
J 0
(1875 5075);
DISPLAY 0.936170 (1875 5075);
PAINT GREEN (1875 5075);
DISPLAY INVISIBLE (1875 5075);
FORCEPROP 1 LAST COMMENT_BODY TRUE
J 0
(1500 5100);
DISPLAY 0.936170 (1500 5100);
PAINT GREEN (1500 5100);
DISPLAY INVISIBLE (1500 5100);
FORCEPROP 2 LAST PATH I2
J 0
(1750 5275);
DISPLAY 0.787234 (1750 5275);
PAINT MONO (1750 5275);
DISPLAY INVISIBLE (1750 5275);
FORCEADD TAP..6
R 2
(850 4200);
FORCEPROP 3 LASTPIN (800 4200) SIG_NAME M_J_DQS_DN<8>
J 0
(810 4210);
DISPLAY 0.659574 (810 4210);
PAINT MONO (810 4210);
DISPLAY INVISIBLE (810 4210);
FORCEPROP 1 LASTPIN (800 4200) BN 8
J 2
(850 4210);
DISPLAY 0.617021 (850 4210);
PAINT PINK (850 4210);
FORCEPROP 2 LAST CDS_LIB mstr_standard
J 0
(850 4200);
DISPLAY 0.787234 (850 4200);
PAINT MONO (850 4200);
DISPLAY INVISIBLE (850 4200);
FORCEPROP 1 LAST BODY_TYPE PLUMBING
J 2
(850 4150);
DISPLAY 1.234043 (850 4150);
PAINT GREEN (850 4150);
DISPLAY INVISIBLE (850 4150);
FORCEPROP 1 LAST HDL_TAP TRUE
J 2
(525 4075);
DISPLAY 1.234043 (525 4075);
PAINT GREEN (525 4075);
DISPLAY INVISIBLE (525 4075);
FORCEPROP 1 LAST PATH I20
J 2
(850 4200);
DISPLAY 0.936170 (850 4200);
PAINT GREEN (850 4200);
DISPLAY INVISIBLE (850 4200);
FORCEADD TAP..6
R 2
(850 4300);
FORCEPROP 3 LASTPIN (800 4300) SIG_NAME M_J_DQS_DN<9>
J 0
(810 4310);
DISPLAY 0.659574 (810 4310);
PAINT MONO (810 4310);
DISPLAY INVISIBLE (810 4310);
FORCEPROP 1 LASTPIN (800 4300) BN 9
J 2
(850 4310);
DISPLAY 0.617021 (850 4310);
PAINT PINK (850 4310);
FORCEPROP 2 LAST CDS_LIB mstr_standard
J 0
(850 4300);
DISPLAY 0.787234 (850 4300);
PAINT MONO (850 4300);
DISPLAY INVISIBLE (850 4300);
FORCEPROP 1 LAST BODY_TYPE PLUMBING
J 2
(850 4250);
DISPLAY 1.234043 (850 4250);
PAINT GREEN (850 4250);
DISPLAY INVISIBLE (850 4250);
FORCEPROP 1 LAST HDL_TAP TRUE
J 2
(525 4175);
DISPLAY 1.234043 (525 4175);
PAINT GREEN (525 4175);
DISPLAY INVISIBLE (525 4175);
FORCEPROP 1 LAST PATH I21
J 2
(850 4300);
DISPLAY 0.936170 (850 4300);
PAINT GREEN (850 4300);
DISPLAY INVISIBLE (850 4300);
FORCEADD TAP..6
R 2
(650 4550);
FORCEPROP 3 LASTPIN (600 4550) SIG_NAME M_J_DQS_DP<11>
J 0
(610 4560);
DISPLAY 0.659574 (610 4560);
PAINT MONO (610 4560);
DISPLAY INVISIBLE (610 4560);
FORCEPROP 1 LASTPIN (600 4550) BN 11
J 2
(650 4560);
DISPLAY 0.617021 (650 4560);
PAINT PINK (650 4560);
FORCEPROP 2 LAST CDS_LIB mstr_standard
J 0
(650 4550);
DISPLAY 0.787234 (650 4550);
PAINT MONO (650 4550);
DISPLAY INVISIBLE (650 4550);
FORCEPROP 1 LAST BODY_TYPE PLUMBING
J 2
(650 4500);
DISPLAY 1.234043 (650 4500);
PAINT GREEN (650 4500);
DISPLAY INVISIBLE (650 4500);
FORCEPROP 1 LAST HDL_TAP TRUE
J 2
(325 4425);
DISPLAY 1.234043 (325 4425);
PAINT GREEN (325 4425);
DISPLAY INVISIBLE (325 4425);
FORCEPROP 1 LAST PATH I22
J 2
(650 4550);
DISPLAY 0.936170 (650 4550);
PAINT GREEN (650 4550);
DISPLAY INVISIBLE (650 4550);
FORCEADD TAP..6
R 2
(650 4450);
FORCEPROP 3 LASTPIN (600 4450) SIG_NAME M_J_DQS_DP<10>
J 0
(610 4460);
DISPLAY 0.659574 (610 4460);
PAINT MONO (610 4460);
DISPLAY INVISIBLE (610 4460);
FORCEPROP 1 LASTPIN (600 4450) BN 10
J 2
(650 4460);
DISPLAY 0.617021 (650 4460);
PAINT PINK (650 4460);
FORCEPROP 2 LAST CDS_LIB mstr_standard
J 0
(650 4450);
DISPLAY 0.787234 (650 4450);
PAINT MONO (650 4450);
DISPLAY INVISIBLE (650 4450);
FORCEPROP 1 LAST BODY_TYPE PLUMBING
J 2
(650 4400);
DISPLAY 1.234043 (650 4400);
PAINT GREEN (650 4400);
DISPLAY INVISIBLE (650 4400);
FORCEPROP 1 LAST HDL_TAP TRUE
J 2
(325 4325);
DISPLAY 1.234043 (325 4325);
PAINT GREEN (325 4325);
DISPLAY INVISIBLE (325 4325);
FORCEPROP 1 LAST PATH I23
J 2
(650 4450);
DISPLAY 0.936170 (650 4450);
PAINT GREEN (650 4450);
DISPLAY INVISIBLE (650 4450);
FORCEADD TAP..6
R 2
(650 4350);
FORCEPROP 3 LASTPIN (600 4350) SIG_NAME M_J_DQS_DP<9>
J 0
(610 4360);
DISPLAY 0.659574 (610 4360);
PAINT MONO (610 4360);
DISPLAY INVISIBLE (610 4360);
FORCEPROP 1 LASTPIN (600 4350) BN 9
J 2
(650 4360);
DISPLAY 0.617021 (650 4360);
PAINT PINK (650 4360);
FORCEPROP 2 LAST CDS_LIB mstr_standard
J 0
(650 4350);
DISPLAY 0.787234 (650 4350);
PAINT MONO (650 4350);
DISPLAY INVISIBLE (650 4350);
FORCEPROP 1 LAST BODY_TYPE PLUMBING
J 2
(650 4300);
DISPLAY 1.234043 (650 4300);
PAINT GREEN (650 4300);
DISPLAY INVISIBLE (650 4300);
FORCEPROP 1 LAST HDL_TAP TRUE
J 2
(325 4225);
DISPLAY 1.234043 (325 4225);
PAINT GREEN (325 4225);
DISPLAY INVISIBLE (325 4225);
FORCEPROP 1 LAST PATH I24
J 2
(650 4350);
DISPLAY 0.936170 (650 4350);
PAINT GREEN (650 4350);
DISPLAY INVISIBLE (650 4350);
FORCEADD TAP..6
R 2
(650 4250);
FORCEPROP 3 LASTPIN (600 4250) SIG_NAME M_J_DQS_DP<8>
J 0
(610 4260);
DISPLAY 0.659574 (610 4260);
PAINT MONO (610 4260);
DISPLAY INVISIBLE (610 4260);
FORCEPROP 1 LASTPIN (600 4250) BN 8
J 2
(650 4260);
DISPLAY 0.617021 (650 4260);
PAINT PINK (650 4260);
FORCEPROP 2 LAST CDS_LIB mstr_standard
J 0
(650 4250);
DISPLAY 0.787234 (650 4250);
PAINT MONO (650 4250);
DISPLAY INVISIBLE (650 4250);
FORCEPROP 1 LAST BODY_TYPE PLUMBING
J 2
(650 4200);
DISPLAY 1.234043 (650 4200);
PAINT GREEN (650 4200);
DISPLAY INVISIBLE (650 4200);
FORCEPROP 1 LAST HDL_TAP TRUE
J 2
(325 4125);
DISPLAY 1.234043 (325 4125);
PAINT GREEN (325 4125);
DISPLAY INVISIBLE (325 4125);
FORCEPROP 1 LAST PATH I25
J 2
(650 4250);
DISPLAY 0.936170 (650 4250);
PAINT GREEN (650 4250);
DISPLAY INVISIBLE (650 4250);
FORCEADD TAP..6
R 2
(650 4150);
FORCEPROP 3 LASTPIN (600 4150) SIG_NAME M_J_DQS_DP<7>
J 0
(610 4160);
DISPLAY 0.659574 (610 4160);
PAINT MONO (610 4160);
DISPLAY INVISIBLE (610 4160);
FORCEPROP 1 LASTPIN (600 4150) BN 7
J 2
(650 4160);
DISPLAY 0.617021 (650 4160);
PAINT PINK (650 4160);
FORCEPROP 2 LAST CDS_LIB mstr_standard
J 0
(650 4150);
DISPLAY 0.787234 (650 4150);
PAINT MONO (650 4150);
DISPLAY INVISIBLE (650 4150);
FORCEPROP 1 LAST BODY_TYPE PLUMBING
J 2
(650 4100);
DISPLAY 1.234043 (650 4100);
PAINT GREEN (650 4100);
DISPLAY INVISIBLE (650 4100);
FORCEPROP 1 LAST HDL_TAP TRUE
J 2
(325 4025);
DISPLAY 1.234043 (325 4025);
PAINT GREEN (325 4025);
DISPLAY INVISIBLE (325 4025);
FORCEPROP 1 LAST PATH I26
J 2
(650 4150);
DISPLAY 0.936170 (650 4150);
PAINT GREEN (650 4150);
DISPLAY INVISIBLE (650 4150);
FORCEADD TAP..6
R 2
(850 4100);
FORCEPROP 3 LASTPIN (800 4100) SIG_NAME M_J_DQS_DN<7>
J 0
(810 4110);
DISPLAY 0.659574 (810 4110);
PAINT MONO (810 4110);
DISPLAY INVISIBLE (810 4110);
FORCEPROP 1 LASTPIN (800 4100) BN 7
J 2
(850 4110);
DISPLAY 0.617021 (850 4110);
PAINT PINK (850 4110);
FORCEPROP 2 LAST CDS_LIB mstr_standard
J 0
(850 4100);
DISPLAY 0.787234 (850 4100);
PAINT MONO (850 4100);
DISPLAY INVISIBLE (850 4100);
FORCEPROP 1 LAST BODY_TYPE PLUMBING
J 2
(850 4050);
DISPLAY 1.234043 (850 4050);
PAINT GREEN (850 4050);
DISPLAY INVISIBLE (850 4050);
FORCEPROP 1 LAST HDL_TAP TRUE
J 2
(525 3975);
DISPLAY 1.234043 (525 3975);
PAINT GREEN (525 3975);
DISPLAY INVISIBLE (525 3975);
FORCEPROP 1 LAST PATH I27
J 2
(850 4100);
DISPLAY 0.936170 (850 4100);
PAINT GREEN (850 4100);
DISPLAY INVISIBLE (850 4100);
FORCEADD TAP..6
R 2
(850 4000);
FORCEPROP 3 LASTPIN (800 4000) SIG_NAME M_J_DQS_DN<6>
J 0
(810 4010);
DISPLAY 0.659574 (810 4010);
PAINT MONO (810 4010);
DISPLAY INVISIBLE (810 4010);
FORCEPROP 1 LASTPIN (800 4000) BN 6
J 2
(850 4010);
DISPLAY 0.617021 (850 4010);
PAINT PINK (850 4010);
FORCEPROP 2 LAST CDS_LIB mstr_standard
J 0
(850 4000);
DISPLAY 0.787234 (850 4000);
PAINT MONO (850 4000);
DISPLAY INVISIBLE (850 4000);
FORCEPROP 1 LAST BODY_TYPE PLUMBING
J 2
(850 3950);
DISPLAY 1.234043 (850 3950);
PAINT GREEN (850 3950);
DISPLAY INVISIBLE (850 3950);
FORCEPROP 1 LAST HDL_TAP TRUE
J 2
(525 3875);
DISPLAY 1.234043 (525 3875);
PAINT GREEN (525 3875);
DISPLAY INVISIBLE (525 3875);
FORCEPROP 1 LAST PATH I28
J 2
(850 4000);
DISPLAY 0.936170 (850 4000);
PAINT GREEN (850 4000);
DISPLAY INVISIBLE (850 4000);
FORCEADD TAP..6
R 2
(850 3900);
FORCEPROP 3 LASTPIN (800 3900) SIG_NAME M_J_DQS_DN<5>
J 0
(810 3910);
DISPLAY 0.659574 (810 3910);
PAINT MONO (810 3910);
DISPLAY INVISIBLE (810 3910);
FORCEPROP 1 LASTPIN (800 3900) BN 5
J 2
(850 3910);
DISPLAY 0.617021 (850 3910);
PAINT PINK (850 3910);
FORCEPROP 2 LAST CDS_LIB mstr_standard
J 0
(850 3900);
DISPLAY 0.787234 (850 3900);
PAINT MONO (850 3900);
DISPLAY INVISIBLE (850 3900);
FORCEPROP 1 LAST BODY_TYPE PLUMBING
J 2
(850 3850);
DISPLAY 1.234043 (850 3850);
PAINT GREEN (850 3850);
DISPLAY INVISIBLE (850 3850);
FORCEPROP 1 LAST HDL_TAP TRUE
J 2
(525 3775);
DISPLAY 1.234043 (525 3775);
PAINT GREEN (525 3775);
DISPLAY INVISIBLE (525 3775);
FORCEPROP 1 LAST PATH I29
J 2
(850 3900);
DISPLAY 0.936170 (850 3900);
PAINT GREEN (850 3900);
DISPLAY INVISIBLE (850 3900);
FORCEADD TAP..6
R 2
(850 5100);
FORCEPROP 3 LASTPIN (800 5100) SIG_NAME M_J_DQS_DN<17>
J 0
(810 5110);
DISPLAY 0.659574 (810 5110);
PAINT MONO (810 5110);
DISPLAY INVISIBLE (810 5110);
FORCEPROP 1 LASTPIN (800 5100) BN 17
J 2
(850 5110);
DISPLAY 0.617021 (850 5110);
PAINT PINK (850 5110);
FORCEPROP 2 LAST CDS_LIB mstr_standard
J 2
(850 5100);
DISPLAY 0.787234 (850 5100);
PAINT MONO (850 5100);
DISPLAY INVISIBLE (850 5100);
FORCEPROP 1 LAST BODY_TYPE PLUMBING
J 2
(850 5050);
DISPLAY 1.234043 (850 5050);
PAINT GREEN (850 5050);
DISPLAY INVISIBLE (850 5050);
FORCEPROP 1 LAST HDL_TAP TRUE
J 2
(525 4975);
DISPLAY 1.234043 (525 4975);
PAINT GREEN (525 4975);
DISPLAY INVISIBLE (525 4975);
FORCEPROP 1 LAST PATH I3
J 2
(850 5100);
DISPLAY 0.936170 (850 5100);
PAINT GREEN (850 5100);
DISPLAY INVISIBLE (850 5100);
FORCEADD TAP..6
R 2
(850 3700);
FORCEPROP 3 LASTPIN (800 3700) SIG_NAME M_J_DQS_DN<3>
J 0
(810 3710);
DISPLAY 0.659574 (810 3710);
PAINT MONO (810 3710);
DISPLAY INVISIBLE (810 3710);
FORCEPROP 1 LASTPIN (800 3700) BN 3
J 2
(850 3710);
DISPLAY 0.617021 (850 3710);
PAINT PINK (850 3710);
FORCEPROP 2 LAST CDS_LIB mstr_standard
J 0
(850 3700);
DISPLAY 0.787234 (850 3700);
PAINT MONO (850 3700);
DISPLAY INVISIBLE (850 3700);
FORCEPROP 1 LAST BODY_TYPE PLUMBING
J 2
(850 3650);
DISPLAY 1.234043 (850 3650);
PAINT GREEN (850 3650);
DISPLAY INVISIBLE (850 3650);
FORCEPROP 1 LAST HDL_TAP TRUE
J 2
(525 3575);
DISPLAY 1.234043 (525 3575);
PAINT GREEN (525 3575);
DISPLAY INVISIBLE (525 3575);
FORCEPROP 1 LAST PATH I30
J 2
(850 3700);
DISPLAY 0.936170 (850 3700);
PAINT GREEN (850 3700);
DISPLAY INVISIBLE (850 3700);
FORCEADD TAP..6
R 2
(850 3800);
FORCEPROP 3 LASTPIN (800 3800) SIG_NAME M_J_DQS_DN<4>
J 0
(810 3810);
DISPLAY 0.659574 (810 3810);
PAINT MONO (810 3810);
DISPLAY INVISIBLE (810 3810);
FORCEPROP 1 LASTPIN (800 3800) BN 4
J 2
(850 3810);
DISPLAY 0.617021 (850 3810);
PAINT PINK (850 3810);
FORCEPROP 2 LAST CDS_LIB mstr_standard
J 0
(850 3800);
DISPLAY 0.787234 (850 3800);
PAINT MONO (850 3800);
DISPLAY INVISIBLE (850 3800);
FORCEPROP 1 LAST BODY_TYPE PLUMBING
J 2
(850 3750);
DISPLAY 1.234043 (850 3750);
PAINT GREEN (850 3750);
DISPLAY INVISIBLE (850 3750);
FORCEPROP 1 LAST HDL_TAP TRUE
J 2
(525 3675);
DISPLAY 1.234043 (525 3675);
PAINT GREEN (525 3675);
DISPLAY INVISIBLE (525 3675);
FORCEPROP 1 LAST PATH I31
J 2
(850 3800);
DISPLAY 0.936170 (850 3800);
PAINT GREEN (850 3800);
DISPLAY INVISIBLE (850 3800);
FORCEADD TAP..6
R 2
(650 4050);
FORCEPROP 3 LASTPIN (600 4050) SIG_NAME M_J_DQS_DP<6>
J 0
(610 4060);
DISPLAY 0.659574 (610 4060);
PAINT MONO (610 4060);
DISPLAY INVISIBLE (610 4060);
FORCEPROP 1 LASTPIN (600 4050) BN 6
J 2
(650 4060);
DISPLAY 0.617021 (650 4060);
PAINT PINK (650 4060);
FORCEPROP 2 LAST CDS_LIB mstr_standard
J 0
(650 4050);
DISPLAY 0.787234 (650 4050);
PAINT MONO (650 4050);
DISPLAY INVISIBLE (650 4050);
FORCEPROP 1 LAST BODY_TYPE PLUMBING
J 2
(650 4000);
DISPLAY 1.234043 (650 4000);
PAINT GREEN (650 4000);
DISPLAY INVISIBLE (650 4000);
FORCEPROP 1 LAST HDL_TAP TRUE
J 2
(325 3925);
DISPLAY 1.234043 (325 3925);
PAINT GREEN (325 3925);
DISPLAY INVISIBLE (325 3925);
FORCEPROP 1 LAST PATH I32
J 2
(650 4050);
DISPLAY 0.936170 (650 4050);
PAINT GREEN (650 4050);
DISPLAY INVISIBLE (650 4050);
FORCEADD TAP..6
R 2
(650 3950);
FORCEPROP 3 LASTPIN (600 3950) SIG_NAME M_J_DQS_DP<5>
J 0
(610 3960);
DISPLAY 0.659574 (610 3960);
PAINT MONO (610 3960);
DISPLAY INVISIBLE (610 3960);
FORCEPROP 1 LASTPIN (600 3950) BN 5
J 2
(650 3960);
DISPLAY 0.617021 (650 3960);
PAINT PINK (650 3960);
FORCEPROP 2 LAST CDS_LIB mstr_standard
J 0
(650 3950);
DISPLAY 0.787234 (650 3950);
PAINT MONO (650 3950);
DISPLAY INVISIBLE (650 3950);
FORCEPROP 1 LAST BODY_TYPE PLUMBING
J 2
(650 3900);
DISPLAY 1.234043 (650 3900);
PAINT GREEN (650 3900);
DISPLAY INVISIBLE (650 3900);
FORCEPROP 1 LAST HDL_TAP TRUE
J 2
(325 3825);
DISPLAY 1.234043 (325 3825);
PAINT GREEN (325 3825);
DISPLAY INVISIBLE (325 3825);
FORCEPROP 1 LAST PATH I33
J 2
(650 3950);
DISPLAY 0.936170 (650 3950);
PAINT GREEN (650 3950);
DISPLAY INVISIBLE (650 3950);
FORCEADD TAP..6
R 2
(650 3850);
FORCEPROP 3 LASTPIN (600 3850) SIG_NAME M_J_DQS_DP<4>
J 0
(610 3860);
DISPLAY 0.659574 (610 3860);
PAINT MONO (610 3860);
DISPLAY INVISIBLE (610 3860);
FORCEPROP 1 LASTPIN (600 3850) BN 4
J 2
(650 3860);
DISPLAY 0.617021 (650 3860);
PAINT PINK (650 3860);
FORCEPROP 2 LAST CDS_LIB mstr_standard
J 0
(650 3850);
DISPLAY 0.787234 (650 3850);
PAINT MONO (650 3850);
DISPLAY INVISIBLE (650 3850);
FORCEPROP 1 LAST BODY_TYPE PLUMBING
J 2
(650 3800);
DISPLAY 1.234043 (650 3800);
PAINT GREEN (650 3800);
DISPLAY INVISIBLE (650 3800);
FORCEPROP 1 LAST HDL_TAP TRUE
J 2
(325 3725);
DISPLAY 1.234043 (325 3725);
PAINT GREEN (325 3725);
DISPLAY INVISIBLE (325 3725);
FORCEPROP 1 LAST PATH I34
J 2
(650 3850);
DISPLAY 0.936170 (650 3850);
PAINT GREEN (650 3850);
DISPLAY INVISIBLE (650 3850);
FORCEADD TAP..6
R 2
(650 3750);
FORCEPROP 3 LASTPIN (600 3750) SIG_NAME M_J_DQS_DP<3>
J 0
(610 3760);
DISPLAY 0.659574 (610 3760);
PAINT MONO (610 3760);
DISPLAY INVISIBLE (610 3760);
FORCEPROP 1 LASTPIN (600 3750) BN 3
J 2
(650 3760);
DISPLAY 0.617021 (650 3760);
PAINT PINK (650 3760);
FORCEPROP 2 LAST CDS_LIB mstr_standard
J 0
(650 3750);
DISPLAY 0.787234 (650 3750);
PAINT MONO (650 3750);
DISPLAY INVISIBLE (650 3750);
FORCEPROP 1 LAST BODY_TYPE PLUMBING
J 2
(650 3700);
DISPLAY 1.234043 (650 3700);
PAINT GREEN (650 3700);
DISPLAY INVISIBLE (650 3700);
FORCEPROP 1 LAST HDL_TAP TRUE
J 2
(325 3625);
DISPLAY 1.234043 (325 3625);
PAINT GREEN (325 3625);
DISPLAY INVISIBLE (325 3625);
FORCEPROP 1 LAST PATH I35
J 2
(650 3750);
DISPLAY 0.936170 (650 3750);
PAINT GREEN (650 3750);
DISPLAY INVISIBLE (650 3750);
FORCEADD TAP..6
R 2
(650 3650);
FORCEPROP 3 LASTPIN (600 3650) SIG_NAME M_J_DQS_DP<2>
J 0
(610 3660);
DISPLAY 0.659574 (610 3660);
PAINT MONO (610 3660);
DISPLAY INVISIBLE (610 3660);
FORCEPROP 1 LASTPIN (600 3650) BN 2
J 2
(650 3660);
DISPLAY 0.617021 (650 3660);
PAINT PINK (650 3660);
FORCEPROP 2 LAST CDS_LIB mstr_standard
J 0
(650 3650);
DISPLAY 0.787234 (650 3650);
PAINT MONO (650 3650);
DISPLAY INVISIBLE (650 3650);
FORCEPROP 1 LAST BODY_TYPE PLUMBING
J 2
(650 3600);
DISPLAY 1.234043 (650 3600);
PAINT GREEN (650 3600);
DISPLAY INVISIBLE (650 3600);
FORCEPROP 1 LAST HDL_TAP TRUE
J 2
(325 3525);
DISPLAY 1.234043 (325 3525);
PAINT GREEN (325 3525);
DISPLAY INVISIBLE (325 3525);
FORCEPROP 1 LAST PATH I36
J 2
(650 3650);
DISPLAY 0.936170 (650 3650);
PAINT GREEN (650 3650);
DISPLAY INVISIBLE (650 3650);
FORCEADD TAP..6
R 2
(850 3500);
FORCEPROP 3 LASTPIN (800 3500) SIG_NAME M_J_DQS_DN<1>
J 0
(810 3510);
DISPLAY 0.659574 (810 3510);
PAINT MONO (810 3510);
DISPLAY INVISIBLE (810 3510);
FORCEPROP 1 LASTPIN (800 3500) BN 1
J 2
(850 3510);
DISPLAY 0.617021 (850 3510);
PAINT PINK (850 3510);
FORCEPROP 2 LAST CDS_LIB mstr_standard
J 0
(850 3500);
DISPLAY 0.787234 (850 3500);
PAINT MONO (850 3500);
DISPLAY INVISIBLE (850 3500);
FORCEPROP 1 LAST BODY_TYPE PLUMBING
J 2
(850 3450);
DISPLAY 1.234043 (850 3450);
PAINT GREEN (850 3450);
DISPLAY INVISIBLE (850 3450);
FORCEPROP 1 LAST HDL_TAP TRUE
J 2
(525 3375);
DISPLAY 1.234043 (525 3375);
PAINT GREEN (525 3375);
DISPLAY INVISIBLE (525 3375);
FORCEPROP 1 LAST PATH I37
J 2
(850 3500);
DISPLAY 0.936170 (850 3500);
PAINT GREEN (850 3500);
DISPLAY INVISIBLE (850 3500);
FORCEADD TAP..6
R 2
(850 3600);
FORCEPROP 3 LASTPIN (800 3600) SIG_NAME M_J_DQS_DN<2>
J 0
(810 3610);
DISPLAY 0.659574 (810 3610);
PAINT MONO (810 3610);
DISPLAY INVISIBLE (810 3610);
FORCEPROP 1 LASTPIN (800 3600) BN 2
J 2
(850 3610);
DISPLAY 0.617021 (850 3610);
PAINT PINK (850 3610);
FORCEPROP 2 LAST CDS_LIB mstr_standard
J 0
(850 3600);
DISPLAY 0.787234 (850 3600);
PAINT MONO (850 3600);
DISPLAY INVISIBLE (850 3600);
FORCEPROP 1 LAST BODY_TYPE PLUMBING
J 2
(850 3550);
DISPLAY 1.234043 (850 3550);
PAINT GREEN (850 3550);
DISPLAY INVISIBLE (850 3550);
FORCEPROP 1 LAST HDL_TAP TRUE
J 2
(525 3475);
DISPLAY 1.234043 (525 3475);
PAINT GREEN (525 3475);
DISPLAY INVISIBLE (525 3475);
FORCEPROP 1 LAST PATH I38
J 2
(850 3600);
DISPLAY 0.936170 (850 3600);
PAINT GREEN (850 3600);
DISPLAY INVISIBLE (850 3600);
FORCEADD TAP..6
R 2
(850 3400);
FORCEPROP 3 LASTPIN (800 3400) SIG_NAME M_J_DQS_DN<0>
J 0
(810 3410);
DISPLAY 0.659574 (810 3410);
PAINT MONO (810 3410);
DISPLAY INVISIBLE (810 3410);
FORCEPROP 1 LASTPIN (800 3400) BN 0
J 2
(850 3410);
DISPLAY 0.617021 (850 3410);
PAINT PINK (850 3410);
FORCEPROP 2 LAST CDS_LIB mstr_standard
J 0
(850 3400);
DISPLAY 0.787234 (850 3400);
PAINT MONO (850 3400);
DISPLAY INVISIBLE (850 3400);
FORCEPROP 1 LAST BODY_TYPE PLUMBING
J 2
(850 3350);
DISPLAY 1.234043 (850 3350);
PAINT GREEN (850 3350);
DISPLAY INVISIBLE (850 3350);
FORCEPROP 1 LAST HDL_TAP TRUE
J 2
(525 3275);
DISPLAY 1.234043 (525 3275);
PAINT GREEN (525 3275);
DISPLAY INVISIBLE (525 3275);
FORCEPROP 1 LAST PATH I39
J 2
(850 3400);
DISPLAY 0.936170 (850 3400);
PAINT GREEN (850 3400);
DISPLAY INVISIBLE (850 3400);
FORCEADD TAP..6
R 2
(850 5000);
FORCEPROP 3 LASTPIN (800 5000) SIG_NAME M_J_DQS_DN<16>
J 0
(810 5010);
DISPLAY 0.659574 (810 5010);
PAINT MONO (810 5010);
DISPLAY INVISIBLE (810 5010);
FORCEPROP 1 LASTPIN (800 5000) BN 16
J 2
(850 5010);
DISPLAY 0.617021 (850 5010);
PAINT PINK (850 5010);
FORCEPROP 2 LAST CDS_LIB mstr_standard
J 0
(850 5000);
DISPLAY 0.787234 (850 5000);
PAINT MONO (850 5000);
DISPLAY INVISIBLE (850 5000);
FORCEPROP 1 LAST BODY_TYPE PLUMBING
J 2
(850 4950);
DISPLAY 1.234043 (850 4950);
PAINT GREEN (850 4950);
DISPLAY INVISIBLE (850 4950);
FORCEPROP 1 LAST HDL_TAP TRUE
J 2
(525 4875);
DISPLAY 1.234043 (525 4875);
PAINT GREEN (525 4875);
DISPLAY INVISIBLE (525 4875);
FORCEPROP 1 LAST PATH I4
J 2
(850 5000);
DISPLAY 0.936170 (850 5000);
PAINT GREEN (850 5000);
DISPLAY INVISIBLE (850 5000);
FORCEADD TAP..6
R 2
(650 3550);
FORCEPROP 3 LASTPIN (600 3550) SIG_NAME M_J_DQS_DP<1>
J 0
(610 3560);
DISPLAY 0.659574 (610 3560);
PAINT MONO (610 3560);
DISPLAY INVISIBLE (610 3560);
FORCEPROP 1 LASTPIN (600 3550) BN 1
J 2
(650 3560);
DISPLAY 0.617021 (650 3560);
PAINT PINK (650 3560);
FORCEPROP 2 LAST CDS_LIB mstr_standard
J 0
(650 3550);
DISPLAY 0.787234 (650 3550);
PAINT MONO (650 3550);
DISPLAY INVISIBLE (650 3550);
FORCEPROP 1 LAST BODY_TYPE PLUMBING
J 2
(650 3500);
DISPLAY 1.234043 (650 3500);
PAINT GREEN (650 3500);
DISPLAY INVISIBLE (650 3500);
FORCEPROP 1 LAST HDL_TAP TRUE
J 2
(325 3425);
DISPLAY 1.234043 (325 3425);
PAINT GREEN (325 3425);
DISPLAY INVISIBLE (325 3425);
FORCEPROP 1 LAST PATH I40
J 2
(650 3550);
DISPLAY 0.936170 (650 3550);
PAINT GREEN (650 3550);
DISPLAY INVISIBLE (650 3550);
FORCEADD TAP..6
R 2
(650 3450);
FORCEPROP 3 LASTPIN (600 3450) SIG_NAME M_J_DQS_DP<0>
J 0
(610 3460);
DISPLAY 0.659574 (610 3460);
PAINT MONO (610 3460);
DISPLAY INVISIBLE (610 3460);
FORCEPROP 1 LASTPIN (600 3450) BN 0
J 2
(650 3460);
DISPLAY 0.617021 (650 3460);
PAINT PINK (650 3460);
FORCEPROP 2 LAST CDS_LIB mstr_standard
J 0
(650 3450);
DISPLAY 0.787234 (650 3450);
PAINT MONO (650 3450);
DISPLAY INVISIBLE (650 3450);
FORCEPROP 1 LAST BODY_TYPE PLUMBING
J 2
(650 3400);
DISPLAY 1.234043 (650 3400);
PAINT GREEN (650 3400);
DISPLAY INVISIBLE (650 3400);
FORCEPROP 1 LAST HDL_TAP TRUE
J 2
(325 3325);
DISPLAY 1.234043 (325 3325);
PAINT GREEN (325 3325);
DISPLAY INVISIBLE (325 3325);
FORCEPROP 1 LAST PATH I41
J 2
(650 3450);
DISPLAY 0.936170 (650 3450);
PAINT GREEN (650 3450);
DISPLAY INVISIBLE (650 3450);
FORCEADD GND..1
R 2
(1050 1050);
FORCEPROP 3 LASTPIN (1050 1100) SIG_NAME GND\g
J 0
(1060 1110);
DISPLAY 0.659574 (1060 1110);
PAINT MONO (1060 1110);
DISPLAY INVISIBLE (1060 1110);
FORCEPROP 1 LAST VOLTAGE 0
J 0
(1050 1050);
PAINT SKYBLUE (1050 1050);
DISPLAY INVISIBLE (1050 1050);
FORCEPROP 1 LAST SIZE 1B
J 2
(975 1000);
DISPLAY 1.170213 (975 1000);
PAINT GREEN (975 1000);
DISPLAY INVISIBLE (975 1000);
FORCEPROP 2 LAST CDS_LIB mstr_symbols
J 0
(1050 1050);
DISPLAY 0.787234 (1050 1050);
PAINT MONO (1050 1050);
DISPLAY INVISIBLE (1050 1050);
FORCEPROP 2 LAST BOM_COST MEM
J 0
(1050 1055);
PAINT ORANGE (1050 1055);
DISPLAY INVISIBLE (1050 1055);
FORCEPROP 1 LAST BODY_TYPE PLUMBING
J 2
(1095 1007);
DISPLAY 0.340426 (1095 1007);
PAINT GREEN (1095 1007);
DISPLAY INVISIBLE (1095 1007);
FORCEPROP 1 LAST PATH I44
J 2
(975 1050);
DISPLAY 0.936170 (975 1050);
PAINT GREEN (975 1050);
DISPLAY INVISIBLE (975 1050);
FORCEPROP 2 LAST ROOM DDR4_CH_J
J 0
(1050 1055);
PAINT ORANGE (1050 1055);
DISPLAY INVISIBLE (1050 1055);
FORCEPROP 1 LAST HDL_POWER GND
J 2
(1050 1200);
DISPLAY 0.553191 (1050 1200);
PAINT GREEN (1050 1200);
DISPLAY INVISIBLE (1050 1200);
FORCEADD OFFPAGE..3
(-1200 4850);
FORCEPROP 2 LAST $XR0 59 
J 0
(-986 4850);
DISPLAY 0.638298 (-986 4850);
PAINT MONO (-986 4850);
FORCEPROP 2 LAST $XR1 81 
J 0
(-896 4850);
DISPLAY 0.638298 (-896 4850);
PAINT MONO (-896 4850);
FORCEPROP 2 LAST CDS_LIB mstr_standard
J 0
(-1200 4850);
DISPLAY 0.787234 (-1200 4850);
PAINT MONO (-1200 4850);
DISPLAY INVISIBLE (-1200 4850);
FORCEPROP 1 LAST OFFPAGE TRUE
J 0
(-875 4725);
DISPLAY 0.936170 (-875 4725);
PAINT GREEN (-875 4725);
DISPLAY INVISIBLE (-875 4725);
FORCEPROP 1 LAST COMMENT_BODY TRUE
J 0
(-1250 4750);
DISPLAY 0.936170 (-1250 4750);
PAINT GREEN (-1250 4750);
DISPLAY INVISIBLE (-1250 4750);
FORCEPROP 2 LAST PATH I45
J 0
(-1000 4925);
DISPLAY 0.787234 (-1000 4925);
PAINT MONO (-1000 4925);
DISPLAY INVISIBLE (-1000 4925);
FORCEADD TAP..6
R 2
(-1750 4750);
FORCEPROP 3 LASTPIN (-1800 4750) SIG_NAME M_J_DQ<62>
J 0
(-1790 4760);
DISPLAY 0.659574 (-1790 4760);
PAINT MONO (-1790 4760);
DISPLAY INVISIBLE (-1790 4760);
FORCEPROP 1 LASTPIN (-1800 4750) BN 62
J 2
(-1750 4760);
DISPLAY 0.617021 (-1750 4760);
PAINT PINK (-1750 4760);
FORCEPROP 2 LAST CDS_LIB mstr_standard
J 2
(-1750 4750);
DISPLAY 0.787234 (-1750 4750);
PAINT MONO (-1750 4750);
DISPLAY INVISIBLE (-1750 4750);
FORCEPROP 1 LAST BODY_TYPE PLUMBING
J 2
(-1750 4700);
DISPLAY 1.234043 (-1750 4700);
PAINT GREEN (-1750 4700);
DISPLAY INVISIBLE (-1750 4700);
FORCEPROP 1 LAST HDL_TAP TRUE
J 2
(-2075 4625);
DISPLAY 1.234043 (-2075 4625);
PAINT GREEN (-2075 4625);
DISPLAY INVISIBLE (-2075 4625);
FORCEPROP 1 LAST PATH I46
J 2
(-1750 4750);
DISPLAY 0.936170 (-1750 4750);
PAINT GREEN (-1750 4750);
DISPLAY INVISIBLE (-1750 4750);
FORCEADD TAP..6
R 2
(-1750 4800);
FORCEPROP 3 LASTPIN (-1800 4800) SIG_NAME M_J_DQ<63>
J 0
(-1790 4810);
DISPLAY 0.659574 (-1790 4810);
PAINT MONO (-1790 4810);
DISPLAY INVISIBLE (-1790 4810);
FORCEPROP 1 LASTPIN (-1800 4800) BN 63
J 2
(-1750 4810);
DISPLAY 0.617021 (-1750 4810);
PAINT PINK (-1750 4810);
FORCEPROP 2 LAST CDS_LIB mstr_standard
J 2
(-1750 4800);
DISPLAY 0.787234 (-1750 4800);
PAINT MONO (-1750 4800);
DISPLAY INVISIBLE (-1750 4800);
FORCEPROP 1 LAST BODY_TYPE PLUMBING
J 2
(-1750 4750);
DISPLAY 1.234043 (-1750 4750);
PAINT GREEN (-1750 4750);
DISPLAY INVISIBLE (-1750 4750);
FORCEPROP 1 LAST HDL_TAP TRUE
J 2
(-2075 4675);
DISPLAY 1.234043 (-2075 4675);
PAINT GREEN (-2075 4675);
DISPLAY INVISIBLE (-2075 4675);
FORCEPROP 1 LAST PATH I47
J 2
(-1750 4800);
DISPLAY 0.936170 (-1750 4800);
PAINT GREEN (-1750 4800);
DISPLAY INVISIBLE (-1750 4800);
FORCEADD TAP..6
R 2
(-1750 4650);
FORCEPROP 3 LASTPIN (-1800 4650) SIG_NAME M_J_DQ<60>
J 0
(-1790 4660);
DISPLAY 0.659574 (-1790 4660);
PAINT MONO (-1790 4660);
DISPLAY INVISIBLE (-1790 4660);
FORCEPROP 1 LASTPIN (-1800 4650) BN 60
J 2
(-1750 4660);
DISPLAY 0.617021 (-1750 4660);
PAINT PINK (-1750 4660);
FORCEPROP 2 LAST CDS_LIB mstr_standard
J 2
(-1750 4650);
DISPLAY 0.787234 (-1750 4650);
PAINT MONO (-1750 4650);
DISPLAY INVISIBLE (-1750 4650);
FORCEPROP 1 LAST BODY_TYPE PLUMBING
J 2
(-1750 4600);
DISPLAY 1.234043 (-1750 4600);
PAINT GREEN (-1750 4600);
DISPLAY INVISIBLE (-1750 4600);
FORCEPROP 1 LAST HDL_TAP TRUE
J 2
(-2075 4525);
DISPLAY 1.234043 (-2075 4525);
PAINT GREEN (-2075 4525);
DISPLAY INVISIBLE (-2075 4525);
FORCEPROP 1 LAST PATH I48
J 2
(-1750 4650);
DISPLAY 0.936170 (-1750 4650);
PAINT GREEN (-1750 4650);
DISPLAY INVISIBLE (-1750 4650);
FORCEADD TAP..6
R 2
(-1750 4700);
FORCEPROP 3 LASTPIN (-1800 4700) SIG_NAME M_J_DQ<61>
J 0
(-1790 4710);
DISPLAY 0.659574 (-1790 4710);
PAINT MONO (-1790 4710);
DISPLAY INVISIBLE (-1790 4710);
FORCEPROP 1 LASTPIN (-1800 4700) BN 61
J 2
(-1750 4710);
DISPLAY 0.617021 (-1750 4710);
PAINT PINK (-1750 4710);
FORCEPROP 2 LAST CDS_LIB mstr_standard
J 2
(-1750 4700);
DISPLAY 0.787234 (-1750 4700);
PAINT MONO (-1750 4700);
DISPLAY INVISIBLE (-1750 4700);
FORCEPROP 1 LAST BODY_TYPE PLUMBING
J 2
(-1750 4650);
DISPLAY 1.234043 (-1750 4650);
PAINT GREEN (-1750 4650);
DISPLAY INVISIBLE (-1750 4650);
FORCEPROP 1 LAST HDL_TAP TRUE
J 2
(-2075 4575);
DISPLAY 1.234043 (-2075 4575);
PAINT GREEN (-2075 4575);
DISPLAY INVISIBLE (-2075 4575);
FORCEPROP 1 LAST PATH I49
J 2
(-1750 4700);
DISPLAY 0.936170 (-1750 4700);
PAINT GREEN (-1750 4700);
DISPLAY INVISIBLE (-1750 4700);
FORCEADD TAP..6
R 2
(850 4900);
FORCEPROP 3 LASTPIN (800 4900) SIG_NAME M_J_DQS_DN<15>
J 0
(810 4910);
DISPLAY 0.659574 (810 4910);
PAINT MONO (810 4910);
DISPLAY INVISIBLE (810 4910);
FORCEPROP 1 LASTPIN (800 4900) BN 15
J 2
(850 4910);
DISPLAY 0.617021 (850 4910);
PAINT PINK (850 4910);
FORCEPROP 2 LAST CDS_LIB mstr_standard
J 0
(850 4900);
DISPLAY 0.787234 (850 4900);
PAINT MONO (850 4900);
DISPLAY INVISIBLE (850 4900);
FORCEPROP 1 LAST BODY_TYPE PLUMBING
J 2
(850 4850);
DISPLAY 1.234043 (850 4850);
PAINT GREEN (850 4850);
DISPLAY INVISIBLE (850 4850);
FORCEPROP 1 LAST HDL_TAP TRUE
J 2
(525 4775);
DISPLAY 1.234043 (525 4775);
PAINT GREEN (525 4775);
DISPLAY INVISIBLE (525 4775);
FORCEPROP 1 LAST PATH I5
J 2
(850 4900);
DISPLAY 0.936170 (850 4900);
PAINT GREEN (850 4900);
DISPLAY INVISIBLE (850 4900);
FORCEADD TAP..6
R 2
(-1750 4600);
FORCEPROP 3 LASTPIN (-1800 4600) SIG_NAME M_J_DQ<59>
J 0
(-1790 4610);
DISPLAY 0.659574 (-1790 4610);
PAINT MONO (-1790 4610);
DISPLAY INVISIBLE (-1790 4610);
FORCEPROP 1 LASTPIN (-1800 4600) BN 59
J 2
(-1750 4610);
DISPLAY 0.617021 (-1750 4610);
PAINT PINK (-1750 4610);
FORCEPROP 2 LAST CDS_LIB mstr_standard
J 2
(-1750 4600);
DISPLAY 0.787234 (-1750 4600);
PAINT MONO (-1750 4600);
DISPLAY INVISIBLE (-1750 4600);
FORCEPROP 1 LAST BODY_TYPE PLUMBING
J 2
(-1750 4550);
DISPLAY 1.234043 (-1750 4550);
PAINT GREEN (-1750 4550);
DISPLAY INVISIBLE (-1750 4550);
FORCEPROP 1 LAST HDL_TAP TRUE
J 2
(-2075 4475);
DISPLAY 1.234043 (-2075 4475);
PAINT GREEN (-2075 4475);
DISPLAY INVISIBLE (-2075 4475);
FORCEPROP 1 LAST PATH I50
J 2
(-1750 4600);
DISPLAY 0.936170 (-1750 4600);
PAINT GREEN (-1750 4600);
DISPLAY INVISIBLE (-1750 4600);
FORCEADD TAP..6
R 2
(-1750 4550);
FORCEPROP 3 LASTPIN (-1800 4550) SIG_NAME M_J_DQ<58>
J 0
(-1790 4560);
DISPLAY 0.659574 (-1790 4560);
PAINT MONO (-1790 4560);
DISPLAY INVISIBLE (-1790 4560);
FORCEPROP 1 LASTPIN (-1800 4550) BN 58
J 2
(-1750 4560);
DISPLAY 0.617021 (-1750 4560);
PAINT PINK (-1750 4560);
FORCEPROP 2 LAST CDS_LIB mstr_standard
J 2
(-1750 4550);
DISPLAY 0.787234 (-1750 4550);
PAINT MONO (-1750 4550);
DISPLAY INVISIBLE (-1750 4550);
FORCEPROP 1 LAST BODY_TYPE PLUMBING
J 2
(-1750 4500);
DISPLAY 1.234043 (-1750 4500);
PAINT GREEN (-1750 4500);
DISPLAY INVISIBLE (-1750 4500);
FORCEPROP 1 LAST HDL_TAP TRUE
J 2
(-2075 4425);
DISPLAY 1.234043 (-2075 4425);
PAINT GREEN (-2075 4425);
DISPLAY INVISIBLE (-2075 4425);
FORCEPROP 1 LAST PATH I51
J 2
(-1750 4550);
DISPLAY 0.936170 (-1750 4550);
PAINT GREEN (-1750 4550);
DISPLAY INVISIBLE (-1750 4550);
FORCEADD TAP..6
R 2
(-1750 4500);
FORCEPROP 3 LASTPIN (-1800 4500) SIG_NAME M_J_DQ<57>
J 0
(-1790 4510);
DISPLAY 0.659574 (-1790 4510);
PAINT MONO (-1790 4510);
DISPLAY INVISIBLE (-1790 4510);
FORCEPROP 1 LASTPIN (-1800 4500) BN 57
J 2
(-1750 4510);
DISPLAY 0.617021 (-1750 4510);
PAINT PINK (-1750 4510);
FORCEPROP 2 LAST CDS_LIB mstr_standard
J 2
(-1750 4500);
DISPLAY 0.787234 (-1750 4500);
PAINT MONO (-1750 4500);
DISPLAY INVISIBLE (-1750 4500);
FORCEPROP 1 LAST BODY_TYPE PLUMBING
J 2
(-1750 4450);
DISPLAY 1.234043 (-1750 4450);
PAINT GREEN (-1750 4450);
DISPLAY INVISIBLE (-1750 4450);
FORCEPROP 1 LAST HDL_TAP TRUE
J 2
(-2075 4375);
DISPLAY 1.234043 (-2075 4375);
PAINT GREEN (-2075 4375);
DISPLAY INVISIBLE (-2075 4375);
FORCEPROP 1 LAST PATH I52
J 2
(-1750 4500);
DISPLAY 0.936170 (-1750 4500);
PAINT GREEN (-1750 4500);
DISPLAY INVISIBLE (-1750 4500);
FORCEADD TAP..6
R 2
(-1750 4300);
FORCEPROP 3 LASTPIN (-1800 4300) SIG_NAME M_J_DQ<53>
J 0
(-1790 4310);
DISPLAY 0.659574 (-1790 4310);
PAINT MONO (-1790 4310);
DISPLAY INVISIBLE (-1790 4310);
FORCEPROP 1 LASTPIN (-1800 4300) BN 53
J 2
(-1750 4310);
DISPLAY 0.617021 (-1750 4310);
PAINT PINK (-1750 4310);
FORCEPROP 2 LAST CDS_LIB mstr_standard
J 2
(-1750 4300);
DISPLAY 0.787234 (-1750 4300);
PAINT MONO (-1750 4300);
DISPLAY INVISIBLE (-1750 4300);
FORCEPROP 1 LAST BODY_TYPE PLUMBING
J 2
(-1750 4250);
DISPLAY 1.234043 (-1750 4250);
PAINT GREEN (-1750 4250);
DISPLAY INVISIBLE (-1750 4250);
FORCEPROP 1 LAST HDL_TAP TRUE
J 2
(-2075 4175);
DISPLAY 1.234043 (-2075 4175);
PAINT GREEN (-2075 4175);
DISPLAY INVISIBLE (-2075 4175);
FORCEPROP 1 LAST PATH I53
J 2
(-1750 4300);
DISPLAY 0.936170 (-1750 4300);
PAINT GREEN (-1750 4300);
DISPLAY INVISIBLE (-1750 4300);
FORCEADD TAP..6
R 2
(-1750 4350);
FORCEPROP 3 LASTPIN (-1800 4350) SIG_NAME M_J_DQ<54>
J 0
(-1790 4360);
DISPLAY 0.659574 (-1790 4360);
PAINT MONO (-1790 4360);
DISPLAY INVISIBLE (-1790 4360);
FORCEPROP 1 LASTPIN (-1800 4350) BN 54
J 2
(-1750 4360);
DISPLAY 0.617021 (-1750 4360);
PAINT PINK (-1750 4360);
FORCEPROP 2 LAST CDS_LIB mstr_standard
J 2
(-1750 4350);
DISPLAY 0.787234 (-1750 4350);
PAINT MONO (-1750 4350);
DISPLAY INVISIBLE (-1750 4350);
FORCEPROP 1 LAST BODY_TYPE PLUMBING
J 2
(-1750 4300);
DISPLAY 1.234043 (-1750 4300);
PAINT GREEN (-1750 4300);
DISPLAY INVISIBLE (-1750 4300);
FORCEPROP 1 LAST HDL_TAP TRUE
J 2
(-2075 4225);
DISPLAY 1.234043 (-2075 4225);
PAINT GREEN (-2075 4225);
DISPLAY INVISIBLE (-2075 4225);
FORCEPROP 1 LAST PATH I54
J 2
(-1750 4350);
DISPLAY 0.936170 (-1750 4350);
PAINT GREEN (-1750 4350);
DISPLAY INVISIBLE (-1750 4350);
FORCEADD TAP..6
R 2
(-1750 4250);
FORCEPROP 3 LASTPIN (-1800 4250) SIG_NAME M_J_DQ<52>
J 0
(-1790 4260);
DISPLAY 0.659574 (-1790 4260);
PAINT MONO (-1790 4260);
DISPLAY INVISIBLE (-1790 4260);
FORCEPROP 1 LASTPIN (-1800 4250) BN 52
J 2
(-1750 4260);
DISPLAY 0.617021 (-1750 4260);
PAINT PINK (-1750 4260);
FORCEPROP 2 LAST CDS_LIB mstr_standard
J 2
(-1750 4250);
DISPLAY 0.787234 (-1750 4250);
PAINT MONO (-1750 4250);
DISPLAY INVISIBLE (-1750 4250);
FORCEPROP 1 LAST BODY_TYPE PLUMBING
J 2
(-1750 4200);
DISPLAY 1.234043 (-1750 4200);
PAINT GREEN (-1750 4200);
DISPLAY INVISIBLE (-1750 4200);
FORCEPROP 1 LAST HDL_TAP TRUE
J 2
(-2075 4125);
DISPLAY 1.234043 (-2075 4125);
PAINT GREEN (-2075 4125);
DISPLAY INVISIBLE (-2075 4125);
FORCEPROP 1 LAST PATH I55
J 2
(-1750 4250);
DISPLAY 0.936170 (-1750 4250);
PAINT GREEN (-1750 4250);
DISPLAY INVISIBLE (-1750 4250);
FORCEADD TAP..6
R 2
(-1750 4400);
FORCEPROP 3 LASTPIN (-1800 4400) SIG_NAME M_J_DQ<55>
J 0
(-1790 4410);
DISPLAY 0.659574 (-1790 4410);
PAINT MONO (-1790 4410);
DISPLAY INVISIBLE (-1790 4410);
FORCEPROP 1 LASTPIN (-1800 4400) BN 55
J 2
(-1750 4410);
DISPLAY 0.617021 (-1750 4410);
PAINT PINK (-1750 4410);
FORCEPROP 2 LAST CDS_LIB mstr_standard
J 2
(-1750 4400);
DISPLAY 0.787234 (-1750 4400);
PAINT MONO (-1750 4400);
DISPLAY INVISIBLE (-1750 4400);
FORCEPROP 1 LAST BODY_TYPE PLUMBING
J 2
(-1750 4350);
DISPLAY 1.234043 (-1750 4350);
PAINT GREEN (-1750 4350);
DISPLAY INVISIBLE (-1750 4350);
FORCEPROP 1 LAST HDL_TAP TRUE
J 2
(-2075 4275);
DISPLAY 1.234043 (-2075 4275);
PAINT GREEN (-2075 4275);
DISPLAY INVISIBLE (-2075 4275);
FORCEPROP 1 LAST PATH I56
J 2
(-1750 4400);
DISPLAY 0.936170 (-1750 4400);
PAINT GREEN (-1750 4400);
DISPLAY INVISIBLE (-1750 4400);
FORCEADD TAP..6
R 2
(-1750 4450);
FORCEPROP 3 LASTPIN (-1800 4450) SIG_NAME M_J_DQ<56>
J 0
(-1790 4460);
DISPLAY 0.659574 (-1790 4460);
PAINT MONO (-1790 4460);
DISPLAY INVISIBLE (-1790 4460);
FORCEPROP 1 LASTPIN (-1800 4450) BN 56
J 2
(-1750 4460);
DISPLAY 0.617021 (-1750 4460);
PAINT PINK (-1750 4460);
FORCEPROP 2 LAST CDS_LIB mstr_standard
J 2
(-1750 4450);
DISPLAY 0.787234 (-1750 4450);
PAINT MONO (-1750 4450);
DISPLAY INVISIBLE (-1750 4450);
FORCEPROP 1 LAST BODY_TYPE PLUMBING
J 2
(-1750 4400);
DISPLAY 1.234043 (-1750 4400);
PAINT GREEN (-1750 4400);
DISPLAY INVISIBLE (-1750 4400);
FORCEPROP 1 LAST HDL_TAP TRUE
J 2
(-2075 4325);
DISPLAY 1.234043 (-2075 4325);
PAINT GREEN (-2075 4325);
DISPLAY INVISIBLE (-2075 4325);
FORCEPROP 1 LAST PATH I57
J 2
(-1750 4450);
DISPLAY 0.936170 (-1750 4450);
PAINT GREEN (-1750 4450);
DISPLAY INVISIBLE (-1750 4450);
FORCEADD TAP..6
R 2
(-1750 4000);
FORCEPROP 3 LASTPIN (-1800 4000) SIG_NAME M_J_DQ<47>
J 0
(-1790 4010);
DISPLAY 0.659574 (-1790 4010);
PAINT MONO (-1790 4010);
DISPLAY INVISIBLE (-1790 4010);
FORCEPROP 1 LASTPIN (-1800 4000) BN 47
J 2
(-1750 4010);
DISPLAY 0.617021 (-1750 4010);
PAINT PINK (-1750 4010);
FORCEPROP 2 LAST CDS_LIB mstr_standard
J 2
(-1750 4000);
DISPLAY 0.787234 (-1750 4000);
PAINT MONO (-1750 4000);
DISPLAY INVISIBLE (-1750 4000);
FORCEPROP 1 LAST BODY_TYPE PLUMBING
J 2
(-1750 3950);
DISPLAY 1.234043 (-1750 3950);
PAINT GREEN (-1750 3950);
DISPLAY INVISIBLE (-1750 3950);
FORCEPROP 1 LAST HDL_TAP TRUE
J 2
(-2075 3875);
DISPLAY 1.234043 (-2075 3875);
PAINT GREEN (-2075 3875);
DISPLAY INVISIBLE (-2075 3875);
FORCEPROP 1 LAST PATH I58
J 2
(-1750 4000);
DISPLAY 0.936170 (-1750 4000);
PAINT GREEN (-1750 4000);
DISPLAY INVISIBLE (-1750 4000);
FORCEADD TAP..6
R 2
(-1750 4050);
FORCEPROP 3 LASTPIN (-1800 4050) SIG_NAME M_J_DQ<48>
J 0
(-1790 4060);
DISPLAY 0.659574 (-1790 4060);
PAINT MONO (-1790 4060);
DISPLAY INVISIBLE (-1790 4060);
FORCEPROP 1 LASTPIN (-1800 4050) BN 48
J 2
(-1750 4060);
DISPLAY 0.617021 (-1750 4060);
PAINT PINK (-1750 4060);
FORCEPROP 2 LAST CDS_LIB mstr_standard
J 2
(-1750 4050);
DISPLAY 0.787234 (-1750 4050);
PAINT MONO (-1750 4050);
DISPLAY INVISIBLE (-1750 4050);
FORCEPROP 1 LAST BODY_TYPE PLUMBING
J 2
(-1750 4000);
DISPLAY 1.234043 (-1750 4000);
PAINT GREEN (-1750 4000);
DISPLAY INVISIBLE (-1750 4000);
FORCEPROP 1 LAST HDL_TAP TRUE
J 2
(-2075 3925);
DISPLAY 1.234043 (-2075 3925);
PAINT GREEN (-2075 3925);
DISPLAY INVISIBLE (-2075 3925);
FORCEPROP 1 LAST PATH I59
J 2
(-1750 4050);
DISPLAY 0.936170 (-1750 4050);
PAINT GREEN (-1750 4050);
DISPLAY INVISIBLE (-1750 4050);
FORCEADD TAP..6
R 2
(850 4800);
FORCEPROP 3 LASTPIN (800 4800) SIG_NAME M_J_DQS_DN<14>
J 0
(810 4810);
DISPLAY 0.659574 (810 4810);
PAINT MONO (810 4810);
DISPLAY INVISIBLE (810 4810);
FORCEPROP 1 LASTPIN (800 4800) BN 14
J 2
(850 4810);
DISPLAY 0.617021 (850 4810);
PAINT PINK (850 4810);
FORCEPROP 2 LAST CDS_LIB mstr_standard
J 0
(850 4800);
DISPLAY 0.787234 (850 4800);
PAINT MONO (850 4800);
DISPLAY INVISIBLE (850 4800);
FORCEPROP 1 LAST BODY_TYPE PLUMBING
J 2
(850 4750);
DISPLAY 1.234043 (850 4750);
PAINT GREEN (850 4750);
DISPLAY INVISIBLE (850 4750);
FORCEPROP 1 LAST HDL_TAP TRUE
J 2
(525 4675);
DISPLAY 1.234043 (525 4675);
PAINT GREEN (525 4675);
DISPLAY INVISIBLE (525 4675);
FORCEPROP 1 LAST PATH I6
J 2
(850 4800);
DISPLAY 0.936170 (850 4800);
PAINT GREEN (850 4800);
DISPLAY INVISIBLE (850 4800);
FORCEADD TAP..6
R 2
(-1750 3950);
FORCEPROP 3 LASTPIN (-1800 3950) SIG_NAME M_J_DQ<46>
J 0
(-1790 3960);
DISPLAY 0.659574 (-1790 3960);
PAINT MONO (-1790 3960);
DISPLAY INVISIBLE (-1790 3960);
FORCEPROP 1 LASTPIN (-1800 3950) BN 46
J 2
(-1750 3960);
DISPLAY 0.617021 (-1750 3960);
PAINT PINK (-1750 3960);
FORCEPROP 2 LAST CDS_LIB mstr_standard
J 2
(-1750 3950);
DISPLAY 0.787234 (-1750 3950);
PAINT MONO (-1750 3950);
DISPLAY INVISIBLE (-1750 3950);
FORCEPROP 1 LAST BODY_TYPE PLUMBING
J 2
(-1750 3900);
DISPLAY 1.234043 (-1750 3900);
PAINT GREEN (-1750 3900);
DISPLAY INVISIBLE (-1750 3900);
FORCEPROP 1 LAST HDL_TAP TRUE
J 2
(-2075 3825);
DISPLAY 1.234043 (-2075 3825);
PAINT GREEN (-2075 3825);
DISPLAY INVISIBLE (-2075 3825);
FORCEPROP 1 LAST PATH I60
J 2
(-1750 3950);
DISPLAY 0.936170 (-1750 3950);
PAINT GREEN (-1750 3950);
DISPLAY INVISIBLE (-1750 3950);
FORCEADD TAP..6
R 2
(-1750 4100);
FORCEPROP 3 LASTPIN (-1800 4100) SIG_NAME M_J_DQ<49>
J 0
(-1790 4110);
DISPLAY 0.659574 (-1790 4110);
PAINT MONO (-1790 4110);
DISPLAY INVISIBLE (-1790 4110);
FORCEPROP 1 LASTPIN (-1800 4100) BN 49
J 2
(-1750 4110);
DISPLAY 0.617021 (-1750 4110);
PAINT PINK (-1750 4110);
FORCEPROP 2 LAST CDS_LIB mstr_standard
J 2
(-1750 4100);
DISPLAY 0.787234 (-1750 4100);
PAINT MONO (-1750 4100);
DISPLAY INVISIBLE (-1750 4100);
FORCEPROP 1 LAST BODY_TYPE PLUMBING
J 2
(-1750 4050);
DISPLAY 1.234043 (-1750 4050);
PAINT GREEN (-1750 4050);
DISPLAY INVISIBLE (-1750 4050);
FORCEPROP 1 LAST HDL_TAP TRUE
J 2
(-2075 3975);
DISPLAY 1.234043 (-2075 3975);
PAINT GREEN (-2075 3975);
DISPLAY INVISIBLE (-2075 3975);
FORCEPROP 1 LAST PATH I61
J 2
(-1750 4100);
DISPLAY 0.936170 (-1750 4100);
PAINT GREEN (-1750 4100);
DISPLAY INVISIBLE (-1750 4100);
FORCEADD TAP..6
R 2
(-1750 4150);
FORCEPROP 3 LASTPIN (-1800 4150) SIG_NAME M_J_DQ<50>
J 0
(-1790 4160);
DISPLAY 0.659574 (-1790 4160);
PAINT MONO (-1790 4160);
DISPLAY INVISIBLE (-1790 4160);
FORCEPROP 1 LASTPIN (-1800 4150) BN 50
J 2
(-1750 4160);
DISPLAY 0.617021 (-1750 4160);
PAINT PINK (-1750 4160);
FORCEPROP 2 LAST CDS_LIB mstr_standard
J 2
(-1750 4150);
DISPLAY 0.787234 (-1750 4150);
PAINT MONO (-1750 4150);
DISPLAY INVISIBLE (-1750 4150);
FORCEPROP 1 LAST BODY_TYPE PLUMBING
J 2
(-1750 4100);
DISPLAY 1.234043 (-1750 4100);
PAINT GREEN (-1750 4100);
DISPLAY INVISIBLE (-1750 4100);
FORCEPROP 1 LAST HDL_TAP TRUE
J 2
(-2075 4025);
DISPLAY 1.234043 (-2075 4025);
PAINT GREEN (-2075 4025);
DISPLAY INVISIBLE (-2075 4025);
FORCEPROP 1 LAST PATH I62
J 2
(-1750 4150);
DISPLAY 0.936170 (-1750 4150);
PAINT GREEN (-1750 4150);
DISPLAY INVISIBLE (-1750 4150);
FORCEADD TAP..6
R 2
(-1750 4200);
FORCEPROP 3 LASTPIN (-1800 4200) SIG_NAME M_J_DQ<51>
J 0
(-1790 4210);
DISPLAY 0.659574 (-1790 4210);
PAINT MONO (-1790 4210);
DISPLAY INVISIBLE (-1790 4210);
FORCEPROP 1 LASTPIN (-1800 4200) BN 51
J 2
(-1750 4210);
DISPLAY 0.617021 (-1750 4210);
PAINT PINK (-1750 4210);
FORCEPROP 2 LAST CDS_LIB mstr_standard
J 2
(-1750 4200);
DISPLAY 0.787234 (-1750 4200);
PAINT MONO (-1750 4200);
DISPLAY INVISIBLE (-1750 4200);
FORCEPROP 1 LAST BODY_TYPE PLUMBING
J 2
(-1750 4150);
DISPLAY 1.234043 (-1750 4150);
PAINT GREEN (-1750 4150);
DISPLAY INVISIBLE (-1750 4150);
FORCEPROP 1 LAST HDL_TAP TRUE
J 2
(-2075 4075);
DISPLAY 1.234043 (-2075 4075);
PAINT GREEN (-2075 4075);
DISPLAY INVISIBLE (-2075 4075);
FORCEPROP 1 LAST PATH I63
J 2
(-1750 4200);
DISPLAY 0.936170 (-1750 4200);
PAINT GREEN (-1750 4200);
DISPLAY INVISIBLE (-1750 4200);
FORCEADD SCONN288_H44441003..2
(-50 4300);
FORCEPROP 1 LAST LOCATION J9U2
J 0
(-450 5400);
DISPLAY 0.617021 (-450 5400);
PAINT AQUA (-450 5400);
FORCEPROP 1 LAST PART_NUMBER H44441-003
J 0
(-450 3200);
DISPLAY 0.617021 (-450 3200);
PAINT BLUE (-450 3200);
FORCEPROP 1 LAST MATERIAL SCONN
J 0
(-450 5350);
DISPLAY 0.617021 (-450 5350);
PAINT SKYBLUE (-450 5350);
FORCEPROP 2 LASTPIN (400 5150) $PN 51
J 0
(410 5160);
DISPLAY 0.617021 (410 5160);
PAINT ORANGE (410 5160);
FORCEPROP 2 LASTPIN (400 5100) $PN 52
J 0
(410 5110);
DISPLAY 0.617021 (410 5110);
PAINT ORANGE (410 5110);
FORCEPROP 2 LASTPIN (400 5050) $PN 132
J 0
(410 5060);
DISPLAY 0.617021 (410 5060);
PAINT ORANGE (410 5060);
FORCEPROP 2 LASTPIN (400 5000) $PN 133
J 0
(410 5010);
DISPLAY 0.617021 (410 5010);
PAINT ORANGE (410 5010);
FORCEPROP 2 LASTPIN (400 4950) $PN 121
J 0
(410 4960);
DISPLAY 0.617021 (410 4960);
PAINT ORANGE (410 4960);
FORCEPROP 2 LASTPIN (400 4900) $PN 122
J 0
(410 4910);
DISPLAY 0.617021 (410 4910);
PAINT ORANGE (410 4910);
FORCEPROP 2 LASTPIN (400 4850) $PN 110
J 0
(410 4860);
DISPLAY 0.617021 (410 4860);
PAINT ORANGE (410 4860);
FORCEPROP 2 LASTPIN (400 4800) $PN 111
J 0
(410 4810);
DISPLAY 0.617021 (410 4810);
PAINT ORANGE (410 4810);
FORCEPROP 2 LASTPIN (400 4750) $PN 99
J 0
(410 4760);
DISPLAY 0.617021 (410 4760);
PAINT ORANGE (410 4760);
FORCEPROP 2 LASTPIN (400 4700) $PN 100
J 0
(410 4710);
DISPLAY 0.617021 (410 4710);
PAINT ORANGE (410 4710);
FORCEPROP 2 LASTPIN (400 4650) $PN 40
J 0
(410 4660);
DISPLAY 0.617021 (410 4660);
PAINT ORANGE (410 4660);
FORCEPROP 2 LASTPIN (400 4600) $PN 41
J 0
(410 4610);
DISPLAY 0.617021 (410 4610);
PAINT ORANGE (410 4610);
FORCEPROP 2 LASTPIN (400 4550) $PN 29
J 0
(410 4560);
DISPLAY 0.617021 (410 4560);
PAINT ORANGE (410 4560);
FORCEPROP 2 LASTPIN (400 4500) $PN 30
J 0
(410 4510);
DISPLAY 0.617021 (410 4510);
PAINT ORANGE (410 4510);
FORCEPROP 2 LASTPIN (400 4450) $PN 18
J 0
(410 4460);
DISPLAY 0.617021 (410 4460);
PAINT ORANGE (410 4460);
FORCEPROP 2 LASTPIN (400 4400) $PN 19
J 0
(410 4410);
DISPLAY 0.617021 (410 4410);
PAINT ORANGE (410 4410);
FORCEPROP 2 LASTPIN (400 4350) $PN 7
J 0
(410 4360);
DISPLAY 0.617021 (410 4360);
PAINT ORANGE (410 4360);
FORCEPROP 2 LASTPIN (400 4300) $PN 8
J 0
(410 4310);
DISPLAY 0.617021 (410 4310);
PAINT ORANGE (410 4310);
FORCEPROP 2 LASTPIN (400 4250) $PN 197
J 0
(410 4260);
DISPLAY 0.617021 (410 4260);
PAINT ORANGE (410 4260);
FORCEPROP 2 LASTPIN (400 4200) $PN 196
J 0
(410 4210);
DISPLAY 0.617021 (410 4210);
PAINT ORANGE (410 4210);
FORCEPROP 2 LASTPIN (400 4150) $PN 278
J 0
(410 4160);
DISPLAY 0.617021 (410 4160);
PAINT ORANGE (410 4160);
FORCEPROP 2 LASTPIN (400 4100) $PN 277
J 0
(410 4110);
DISPLAY 0.617021 (410 4110);
PAINT ORANGE (410 4110);
FORCEPROP 2 LASTPIN (400 4050) $PN 267
J 0
(410 4060);
DISPLAY 0.617021 (410 4060);
PAINT ORANGE (410 4060);
FORCEPROP 2 LASTPIN (400 4000) $PN 266
J 0
(410 4010);
DISPLAY 0.617021 (410 4010);
PAINT ORANGE (410 4010);
FORCEPROP 2 LASTPIN (400 3950) $PN 256
J 0
(410 3960);
DISPLAY 0.617021 (410 3960);
PAINT ORANGE (410 3960);
FORCEPROP 2 LASTPIN (400 3900) $PN 255
J 0
(410 3910);
DISPLAY 0.617021 (410 3910);
PAINT ORANGE (410 3910);
FORCEPROP 2 LASTPIN (400 3850) $PN 245
J 0
(410 3860);
DISPLAY 0.617021 (410 3860);
PAINT ORANGE (410 3860);
FORCEPROP 2 LASTPIN (400 3800) $PN 244
J 0
(410 3810);
DISPLAY 0.617021 (410 3810);
PAINT ORANGE (410 3810);
FORCEPROP 2 LASTPIN (400 3750) $PN 186
J 0
(410 3760);
DISPLAY 0.617021 (410 3760);
PAINT ORANGE (410 3760);
FORCEPROP 2 LASTPIN (400 3700) $PN 185
J 0
(410 3710);
DISPLAY 0.617021 (410 3710);
PAINT ORANGE (410 3710);
FORCEPROP 2 LASTPIN (400 3650) $PN 175
J 0
(410 3660);
DISPLAY 0.617021 (410 3660);
PAINT ORANGE (410 3660);
FORCEPROP 2 LASTPIN (400 3600) $PN 174
J 0
(410 3610);
DISPLAY 0.617021 (410 3610);
PAINT ORANGE (410 3610);
FORCEPROP 2 LASTPIN (400 3550) $PN 164
J 0
(410 3560);
DISPLAY 0.617021 (410 3560);
PAINT ORANGE (410 3560);
FORCEPROP 2 LASTPIN (400 3500) $PN 163
J 0
(410 3510);
DISPLAY 0.617021 (410 3510);
PAINT ORANGE (410 3510);
FORCEPROP 2 LASTPIN (400 3450) $PN 153
J 0
(410 3460);
DISPLAY 0.617021 (410 3460);
PAINT ORANGE (410 3460);
FORCEPROP 2 LASTPIN (400 3400) $PN 152
J 0
(410 3410);
DISPLAY 0.617021 (410 3410);
PAINT ORANGE (410 3410);
FORCEPROP 1 LAST PACK_TYPE PIP
J 0
(-450 5450);
PAINT SKYBLUE (-450 5450);
DISPLAY INVISIBLE (-450 5450);
FORCEPROP 2 LAST BOM_COST MEM
J 0
(-50 4300);
PAINT ORANGE (-50 4300);
DISPLAY INVISIBLE (-50 4300);
FORCEPROP 2 LAST CDS_LIB mstr_sconn
J 0
(-50 4300);
PAINT ORANGE (-50 4300);
DISPLAY INVISIBLE (-50 4300);
FORCEPROP 2 LAST SEC_TYPE PIP
J 0
(-450 5450);
DISPLAY 1.021277 (-450 5450);
PAINT ORANGE (-450 5450);
DISPLAY INVISIBLE (-450 5450);
FORCEPROP 2 LAST SEC 2
J 0
(-450 5450);
DISPLAY 0.680851 (-450 5450);
PAINT MONO (-450 5450);
DISPLAY INVISIBLE (-450 5450);
FORCEPROP 2 LAST CDS_LOCATION J9U2
J 0
(-450 5400);
DISPLAY 0.617021 (-450 5400);
PAINT AQUA (-450 5400);
DISPLAY INVISIBLE (-450 5400);
FORCEPROP 1 LAST PATH I64
J 0
(-50 5350);
PAINT GREEN (-50 5350);
DISPLAY INVISIBLE (-50 5350);
FORCEPROP 2 LAST ROOM DDR4_CH_J
J 0
(-50 4300);
PAINT ORANGE (-50 4300);
DISPLAY INVISIBLE (-50 4300);
FORCEADD TAP..6
R 2
(-1750 3800);
FORCEPROP 3 LASTPIN (-1800 3800) SIG_NAME M_J_DQ<43>
J 0
(-1790 3810);
DISPLAY 0.659574 (-1790 3810);
PAINT MONO (-1790 3810);
DISPLAY INVISIBLE (-1790 3810);
FORCEPROP 1 LASTPIN (-1800 3800) BN 43
J 2
(-1750 3810);
DISPLAY 0.617021 (-1750 3810);
PAINT PINK (-1750 3810);
FORCEPROP 2 LAST CDS_LIB mstr_standard
J 2
(-1750 3800);
DISPLAY 0.787234 (-1750 3800);
PAINT MONO (-1750 3800);
DISPLAY INVISIBLE (-1750 3800);
FORCEPROP 1 LAST BODY_TYPE PLUMBING
J 2
(-1750 3750);
DISPLAY 1.234043 (-1750 3750);
PAINT GREEN (-1750 3750);
DISPLAY INVISIBLE (-1750 3750);
FORCEPROP 1 LAST HDL_TAP TRUE
J 2
(-2075 3675);
DISPLAY 1.234043 (-2075 3675);
PAINT GREEN (-2075 3675);
DISPLAY INVISIBLE (-2075 3675);
FORCEPROP 1 LAST PATH I65
J 2
(-1750 3800);
DISPLAY 0.936170 (-1750 3800);
PAINT GREEN (-1750 3800);
DISPLAY INVISIBLE (-1750 3800);
FORCEADD TAP..6
R 2
(-1750 3750);
FORCEPROP 3 LASTPIN (-1800 3750) SIG_NAME M_J_DQ<42>
J 0
(-1790 3760);
DISPLAY 0.659574 (-1790 3760);
PAINT MONO (-1790 3760);
DISPLAY INVISIBLE (-1790 3760);
FORCEPROP 1 LASTPIN (-1800 3750) BN 42
J 2
(-1750 3760);
DISPLAY 0.617021 (-1750 3760);
PAINT PINK (-1750 3760);
FORCEPROP 2 LAST CDS_LIB mstr_standard
J 2
(-1750 3750);
DISPLAY 0.787234 (-1750 3750);
PAINT MONO (-1750 3750);
DISPLAY INVISIBLE (-1750 3750);
FORCEPROP 1 LAST BODY_TYPE PLUMBING
J 2
(-1750 3700);
DISPLAY 1.234043 (-1750 3700);
PAINT GREEN (-1750 3700);
DISPLAY INVISIBLE (-1750 3700);
FORCEPROP 1 LAST HDL_TAP TRUE
J 2
(-2075 3625);
DISPLAY 1.234043 (-2075 3625);
PAINT GREEN (-2075 3625);
DISPLAY INVISIBLE (-2075 3625);
FORCEPROP 1 LAST PATH I66
J 2
(-1750 3750);
DISPLAY 0.936170 (-1750 3750);
PAINT GREEN (-1750 3750);
DISPLAY INVISIBLE (-1750 3750);
FORCEADD TAP..6
R 2
(-1750 3700);
FORCEPROP 3 LASTPIN (-1800 3700) SIG_NAME M_J_DQ<41>
J 0
(-1790 3710);
DISPLAY 0.659574 (-1790 3710);
PAINT MONO (-1790 3710);
DISPLAY INVISIBLE (-1790 3710);
FORCEPROP 1 LASTPIN (-1800 3700) BN 41
J 2
(-1750 3710);
DISPLAY 0.617021 (-1750 3710);
PAINT PINK (-1750 3710);
FORCEPROP 2 LAST CDS_LIB mstr_standard
J 2
(-1750 3700);
DISPLAY 0.787234 (-1750 3700);
PAINT MONO (-1750 3700);
DISPLAY INVISIBLE (-1750 3700);
FORCEPROP 1 LAST BODY_TYPE PLUMBING
J 2
(-1750 3650);
DISPLAY 1.234043 (-1750 3650);
PAINT GREEN (-1750 3650);
DISPLAY INVISIBLE (-1750 3650);
FORCEPROP 1 LAST HDL_TAP TRUE
J 2
(-2075 3575);
DISPLAY 1.234043 (-2075 3575);
PAINT GREEN (-2075 3575);
DISPLAY INVISIBLE (-2075 3575);
FORCEPROP 1 LAST PATH I67
J 2
(-1750 3700);
DISPLAY 0.936170 (-1750 3700);
PAINT GREEN (-1750 3700);
DISPLAY INVISIBLE (-1750 3700);
FORCEADD TAP..6
R 2
(-1750 3850);
FORCEPROP 3 LASTPIN (-1800 3850) SIG_NAME M_J_DQ<44>
J 0
(-1790 3860);
DISPLAY 0.659574 (-1790 3860);
PAINT MONO (-1790 3860);
DISPLAY INVISIBLE (-1790 3860);
FORCEPROP 1 LASTPIN (-1800 3850) BN 44
J 2
(-1750 3860);
DISPLAY 0.617021 (-1750 3860);
PAINT PINK (-1750 3860);
FORCEPROP 2 LAST CDS_LIB mstr_standard
J 2
(-1750 3850);
DISPLAY 0.787234 (-1750 3850);
PAINT MONO (-1750 3850);
DISPLAY INVISIBLE (-1750 3850);
FORCEPROP 1 LAST BODY_TYPE PLUMBING
J 2
(-1750 3800);
DISPLAY 1.234043 (-1750 3800);
PAINT GREEN (-1750 3800);
DISPLAY INVISIBLE (-1750 3800);
FORCEPROP 1 LAST HDL_TAP TRUE
J 2
(-2075 3725);
DISPLAY 1.234043 (-2075 3725);
PAINT GREEN (-2075 3725);
DISPLAY INVISIBLE (-2075 3725);
FORCEPROP 1 LAST PATH I68
J 2
(-1750 3850);
DISPLAY 0.936170 (-1750 3850);
PAINT GREEN (-1750 3850);
DISPLAY INVISIBLE (-1750 3850);
FORCEADD TAP..6
R 2
(-1750 3900);
FORCEPROP 3 LASTPIN (-1800 3900) SIG_NAME M_J_DQ<45>
J 0
(-1790 3910);
DISPLAY 0.659574 (-1790 3910);
PAINT MONO (-1790 3910);
DISPLAY INVISIBLE (-1790 3910);
FORCEPROP 1 LASTPIN (-1800 3900) BN 45
J 2
(-1750 3910);
DISPLAY 0.617021 (-1750 3910);
PAINT PINK (-1750 3910);
FORCEPROP 2 LAST CDS_LIB mstr_standard
J 2
(-1750 3900);
DISPLAY 0.787234 (-1750 3900);
PAINT MONO (-1750 3900);
DISPLAY INVISIBLE (-1750 3900);
FORCEPROP 1 LAST BODY_TYPE PLUMBING
J 2
(-1750 3850);
DISPLAY 1.234043 (-1750 3850);
PAINT GREEN (-1750 3850);
DISPLAY INVISIBLE (-1750 3850);
FORCEPROP 1 LAST HDL_TAP TRUE
J 2
(-2075 3775);
DISPLAY 1.234043 (-2075 3775);
PAINT GREEN (-2075 3775);
DISPLAY INVISIBLE (-2075 3775);
FORCEPROP 1 LAST PATH I69
J 2
(-1750 3900);
DISPLAY 0.936170 (-1750 3900);
PAINT GREEN (-1750 3900);
DISPLAY INVISIBLE (-1750 3900);
FORCEADD TAP..6
R 2
(850 4700);
FORCEPROP 3 LASTPIN (800 4700) SIG_NAME M_J_DQS_DN<13>
J 0
(810 4710);
DISPLAY 0.659574 (810 4710);
PAINT MONO (810 4710);
DISPLAY INVISIBLE (810 4710);
FORCEPROP 1 LASTPIN (800 4700) BN 13
J 2
(850 4710);
DISPLAY 0.617021 (850 4710);
PAINT PINK (850 4710);
FORCEPROP 2 LAST CDS_LIB mstr_standard
J 0
(850 4700);
DISPLAY 0.787234 (850 4700);
PAINT MONO (850 4700);
DISPLAY INVISIBLE (850 4700);
FORCEPROP 1 LAST BODY_TYPE PLUMBING
J 2
(850 4650);
DISPLAY 1.234043 (850 4650);
PAINT GREEN (850 4650);
DISPLAY INVISIBLE (850 4650);
FORCEPROP 1 LAST HDL_TAP TRUE
J 2
(525 4575);
DISPLAY 1.234043 (525 4575);
PAINT GREEN (525 4575);
DISPLAY INVISIBLE (525 4575);
FORCEPROP 1 LAST PATH I7
J 2
(850 4700);
DISPLAY 0.936170 (850 4700);
PAINT GREEN (850 4700);
DISPLAY INVISIBLE (850 4700);
FORCEADD TAP..6
R 2
(-1750 3550);
FORCEPROP 3 LASTPIN (-1800 3550) SIG_NAME M_J_DQ<38>
J 0
(-1790 3560);
DISPLAY 0.659574 (-1790 3560);
PAINT MONO (-1790 3560);
DISPLAY INVISIBLE (-1790 3560);
FORCEPROP 1 LASTPIN (-1800 3550) BN 38
J 2
(-1750 3560);
DISPLAY 0.617021 (-1750 3560);
PAINT PINK (-1750 3560);
FORCEPROP 2 LAST CDS_LIB mstr_standard
J 2
(-1750 3550);
DISPLAY 0.787234 (-1750 3550);
PAINT MONO (-1750 3550);
DISPLAY INVISIBLE (-1750 3550);
FORCEPROP 1 LAST BODY_TYPE PLUMBING
J 2
(-1750 3500);
DISPLAY 1.234043 (-1750 3500);
PAINT GREEN (-1750 3500);
DISPLAY INVISIBLE (-1750 3500);
FORCEPROP 1 LAST HDL_TAP TRUE
J 2
(-2075 3425);
DISPLAY 1.234043 (-2075 3425);
PAINT GREEN (-2075 3425);
DISPLAY INVISIBLE (-2075 3425);
FORCEPROP 1 LAST PATH I70
J 2
(-1750 3550);
DISPLAY 0.936170 (-1750 3550);
PAINT GREEN (-1750 3550);
DISPLAY INVISIBLE (-1750 3550);
FORCEADD TAP..6
R 2
(-1750 3500);
FORCEPROP 3 LASTPIN (-1800 3500) SIG_NAME M_J_DQ<37>
J 0
(-1790 3510);
DISPLAY 0.659574 (-1790 3510);
PAINT MONO (-1790 3510);
DISPLAY INVISIBLE (-1790 3510);
FORCEPROP 1 LASTPIN (-1800 3500) BN 37
J 2
(-1750 3510);
DISPLAY 0.617021 (-1750 3510);
PAINT PINK (-1750 3510);
FORCEPROP 2 LAST CDS_LIB mstr_standard
J 2
(-1750 3500);
DISPLAY 0.787234 (-1750 3500);
PAINT MONO (-1750 3500);
DISPLAY INVISIBLE (-1750 3500);
FORCEPROP 1 LAST BODY_TYPE PLUMBING
J 2
(-1750 3450);
DISPLAY 1.234043 (-1750 3450);
PAINT GREEN (-1750 3450);
DISPLAY INVISIBLE (-1750 3450);
FORCEPROP 1 LAST HDL_TAP TRUE
J 2
(-2075 3375);
DISPLAY 1.234043 (-2075 3375);
PAINT GREEN (-2075 3375);
DISPLAY INVISIBLE (-2075 3375);
FORCEPROP 1 LAST PATH I71
J 2
(-1750 3500);
DISPLAY 0.936170 (-1750 3500);
PAINT GREEN (-1750 3500);
DISPLAY INVISIBLE (-1750 3500);
FORCEADD TAP..6
R 2
(-1750 3450);
FORCEPROP 3 LASTPIN (-1800 3450) SIG_NAME M_J_DQ<36>
J 0
(-1790 3460);
DISPLAY 0.659574 (-1790 3460);
PAINT MONO (-1790 3460);
DISPLAY INVISIBLE (-1790 3460);
FORCEPROP 1 LASTPIN (-1800 3450) BN 36
J 2
(-1750 3460);
DISPLAY 0.617021 (-1750 3460);
PAINT PINK (-1750 3460);
FORCEPROP 2 LAST CDS_LIB mstr_standard
J 2
(-1750 3450);
DISPLAY 0.787234 (-1750 3450);
PAINT MONO (-1750 3450);
DISPLAY INVISIBLE (-1750 3450);
FORCEPROP 1 LAST BODY_TYPE PLUMBING
J 2
(-1750 3400);
DISPLAY 1.234043 (-1750 3400);
PAINT GREEN (-1750 3400);
DISPLAY INVISIBLE (-1750 3400);
FORCEPROP 1 LAST HDL_TAP TRUE
J 2
(-2075 3325);
DISPLAY 1.234043 (-2075 3325);
PAINT GREEN (-2075 3325);
DISPLAY INVISIBLE (-2075 3325);
FORCEPROP 1 LAST PATH I72
J 2
(-1750 3450);
DISPLAY 0.936170 (-1750 3450);
PAINT GREEN (-1750 3450);
DISPLAY INVISIBLE (-1750 3450);
FORCEADD TAP..6
R 2
(-1750 3650);
FORCEPROP 3 LASTPIN (-1800 3650) SIG_NAME M_J_DQ<40>
J 0
(-1790 3660);
DISPLAY 0.659574 (-1790 3660);
PAINT MONO (-1790 3660);
DISPLAY INVISIBLE (-1790 3660);
FORCEPROP 1 LASTPIN (-1800 3650) BN 40
J 2
(-1750 3660);
DISPLAY 0.617021 (-1750 3660);
PAINT PINK (-1750 3660);
FORCEPROP 2 LAST CDS_LIB mstr_standard
J 2
(-1750 3650);
DISPLAY 0.787234 (-1750 3650);
PAINT MONO (-1750 3650);
DISPLAY INVISIBLE (-1750 3650);
FORCEPROP 1 LAST BODY_TYPE PLUMBING
J 2
(-1750 3600);
DISPLAY 1.234043 (-1750 3600);
PAINT GREEN (-1750 3600);
DISPLAY INVISIBLE (-1750 3600);
FORCEPROP 1 LAST HDL_TAP TRUE
J 2
(-2075 3525);
DISPLAY 1.234043 (-2075 3525);
PAINT GREEN (-2075 3525);
DISPLAY INVISIBLE (-2075 3525);
FORCEPROP 1 LAST PATH I73
J 2
(-1750 3650);
DISPLAY 0.936170 (-1750 3650);
PAINT GREEN (-1750 3650);
DISPLAY INVISIBLE (-1750 3650);
FORCEADD TAP..6
R 2
(-1750 3600);
FORCEPROP 3 LASTPIN (-1800 3600) SIG_NAME M_J_DQ<39>
J 0
(-1790 3610);
DISPLAY 0.659574 (-1790 3610);
PAINT MONO (-1790 3610);
DISPLAY INVISIBLE (-1790 3610);
FORCEPROP 1 LASTPIN (-1800 3600) BN 39
J 2
(-1750 3610);
DISPLAY 0.617021 (-1750 3610);
PAINT PINK (-1750 3610);
FORCEPROP 2 LAST CDS_LIB mstr_standard
J 2
(-1750 3600);
DISPLAY 0.787234 (-1750 3600);
PAINT MONO (-1750 3600);
DISPLAY INVISIBLE (-1750 3600);
FORCEPROP 1 LAST BODY_TYPE PLUMBING
J 2
(-1750 3550);
DISPLAY 1.234043 (-1750 3550);
PAINT GREEN (-1750 3550);
DISPLAY INVISIBLE (-1750 3550);
FORCEPROP 1 LAST HDL_TAP TRUE
J 2
(-2075 3475);
DISPLAY 1.234043 (-2075 3475);
PAINT GREEN (-2075 3475);
DISPLAY INVISIBLE (-2075 3475);
FORCEPROP 1 LAST PATH I74
J 2
(-1750 3600);
DISPLAY 0.936170 (-1750 3600);
PAINT GREEN (-1750 3600);
DISPLAY INVISIBLE (-1750 3600);
FORCEADD TAP..6
R 2
(-1750 3300);
FORCEPROP 3 LASTPIN (-1800 3300) SIG_NAME M_J_DQ<33>
J 0
(-1790 3310);
DISPLAY 0.659574 (-1790 3310);
PAINT MONO (-1790 3310);
DISPLAY INVISIBLE (-1790 3310);
FORCEPROP 1 LASTPIN (-1800 3300) BN 33
J 2
(-1750 3310);
DISPLAY 0.617021 (-1750 3310);
PAINT PINK (-1750 3310);
FORCEPROP 2 LAST CDS_LIB mstr_standard
J 2
(-1750 3300);
DISPLAY 0.787234 (-1750 3300);
PAINT MONO (-1750 3300);
DISPLAY INVISIBLE (-1750 3300);
FORCEPROP 1 LAST BODY_TYPE PLUMBING
J 2
(-1750 3250);
DISPLAY 1.234043 (-1750 3250);
PAINT GREEN (-1750 3250);
DISPLAY INVISIBLE (-1750 3250);
FORCEPROP 1 LAST HDL_TAP TRUE
J 2
(-2075 3175);
DISPLAY 1.234043 (-2075 3175);
PAINT GREEN (-2075 3175);
DISPLAY INVISIBLE (-2075 3175);
FORCEPROP 1 LAST PATH I75
J 2
(-1750 3300);
DISPLAY 0.936170 (-1750 3300);
PAINT GREEN (-1750 3300);
DISPLAY INVISIBLE (-1750 3300);
FORCEADD TAP..6
R 2
(-1750 3250);
FORCEPROP 3 LASTPIN (-1800 3250) SIG_NAME M_J_DQ<32>
J 0
(-1790 3260);
DISPLAY 0.659574 (-1790 3260);
PAINT MONO (-1790 3260);
DISPLAY INVISIBLE (-1790 3260);
FORCEPROP 1 LASTPIN (-1800 3250) BN 32
J 2
(-1750 3260);
DISPLAY 0.617021 (-1750 3260);
PAINT PINK (-1750 3260);
FORCEPROP 2 LAST CDS_LIB mstr_standard
J 2
(-1750 3250);
DISPLAY 0.787234 (-1750 3250);
PAINT MONO (-1750 3250);
DISPLAY INVISIBLE (-1750 3250);
FORCEPROP 1 LAST BODY_TYPE PLUMBING
J 2
(-1750 3200);
DISPLAY 1.234043 (-1750 3200);
PAINT GREEN (-1750 3200);
DISPLAY INVISIBLE (-1750 3200);
FORCEPROP 1 LAST HDL_TAP TRUE
J 2
(-2075 3125);
DISPLAY 1.234043 (-2075 3125);
PAINT GREEN (-2075 3125);
DISPLAY INVISIBLE (-2075 3125);
FORCEPROP 1 LAST PATH I76
J 2
(-1750 3250);
DISPLAY 0.936170 (-1750 3250);
PAINT GREEN (-1750 3250);
DISPLAY INVISIBLE (-1750 3250);
FORCEADD TAP..6
R 2
(-1750 3200);
FORCEPROP 3 LASTPIN (-1800 3200) SIG_NAME M_J_DQ<31>
J 0
(-1790 3210);
DISPLAY 0.659574 (-1790 3210);
PAINT MONO (-1790 3210);
DISPLAY INVISIBLE (-1790 3210);
FORCEPROP 1 LASTPIN (-1800 3200) BN 31
J 2
(-1750 3210);
DISPLAY 0.617021 (-1750 3210);
PAINT PINK (-1750 3210);
FORCEPROP 2 LAST CDS_LIB mstr_standard
J 2
(-1750 3200);
DISPLAY 0.787234 (-1750 3200);
PAINT MONO (-1750 3200);
DISPLAY INVISIBLE (-1750 3200);
FORCEPROP 1 LAST BODY_TYPE PLUMBING
J 2
(-1750 3150);
DISPLAY 1.234043 (-1750 3150);
PAINT GREEN (-1750 3150);
DISPLAY INVISIBLE (-1750 3150);
FORCEPROP 1 LAST HDL_TAP TRUE
J 2
(-2075 3075);
DISPLAY 1.234043 (-2075 3075);
PAINT GREEN (-2075 3075);
DISPLAY INVISIBLE (-2075 3075);
FORCEPROP 1 LAST PATH I77
J 2
(-1750 3200);
DISPLAY 0.936170 (-1750 3200);
PAINT GREEN (-1750 3200);
DISPLAY INVISIBLE (-1750 3200);
FORCEADD TAP..6
R 2
(-1750 3400);
FORCEPROP 3 LASTPIN (-1800 3400) SIG_NAME M_J_DQ<35>
J 0
(-1790 3410);
DISPLAY 0.659574 (-1790 3410);
PAINT MONO (-1790 3410);
DISPLAY INVISIBLE (-1790 3410);
FORCEPROP 1 LASTPIN (-1800 3400) BN 35
J 2
(-1750 3410);
DISPLAY 0.617021 (-1750 3410);
PAINT PINK (-1750 3410);
FORCEPROP 2 LAST CDS_LIB mstr_standard
J 2
(-1750 3400);
DISPLAY 0.787234 (-1750 3400);
PAINT MONO (-1750 3400);
DISPLAY INVISIBLE (-1750 3400);
FORCEPROP 1 LAST BODY_TYPE PLUMBING
J 2
(-1750 3350);
DISPLAY 1.234043 (-1750 3350);
PAINT GREEN (-1750 3350);
DISPLAY INVISIBLE (-1750 3350);
FORCEPROP 1 LAST HDL_TAP TRUE
J 2
(-2075 3275);
DISPLAY 1.234043 (-2075 3275);
PAINT GREEN (-2075 3275);
DISPLAY INVISIBLE (-2075 3275);
FORCEPROP 1 LAST PATH I78
J 2
(-1750 3400);
DISPLAY 0.936170 (-1750 3400);
PAINT GREEN (-1750 3400);
DISPLAY INVISIBLE (-1750 3400);
FORCEADD TAP..6
R 2
(-1750 3350);
FORCEPROP 3 LASTPIN (-1800 3350) SIG_NAME M_J_DQ<34>
J 0
(-1790 3360);
DISPLAY 0.659574 (-1790 3360);
PAINT MONO (-1790 3360);
DISPLAY INVISIBLE (-1790 3360);
FORCEPROP 1 LASTPIN (-1800 3350) BN 34
J 2
(-1750 3360);
DISPLAY 0.617021 (-1750 3360);
PAINT PINK (-1750 3360);
FORCEPROP 2 LAST CDS_LIB mstr_standard
J 2
(-1750 3350);
DISPLAY 0.787234 (-1750 3350);
PAINT MONO (-1750 3350);
DISPLAY INVISIBLE (-1750 3350);
FORCEPROP 1 LAST BODY_TYPE PLUMBING
J 2
(-1750 3300);
DISPLAY 1.234043 (-1750 3300);
PAINT GREEN (-1750 3300);
DISPLAY INVISIBLE (-1750 3300);
FORCEPROP 1 LAST HDL_TAP TRUE
J 2
(-2075 3225);
DISPLAY 1.234043 (-2075 3225);
PAINT GREEN (-2075 3225);
DISPLAY INVISIBLE (-2075 3225);
FORCEPROP 1 LAST PATH I79
J 2
(-1750 3350);
DISPLAY 0.936170 (-1750 3350);
PAINT GREEN (-1750 3350);
DISPLAY INVISIBLE (-1750 3350);
FORCEADD TAP..6
R 2
(650 5050);
FORCEPROP 3 LASTPIN (600 5050) SIG_NAME M_J_DQS_DP<16>
J 0
(610 5060);
DISPLAY 0.659574 (610 5060);
PAINT MONO (610 5060);
DISPLAY INVISIBLE (610 5060);
FORCEPROP 1 LASTPIN (600 5050) BN 16
J 2
(650 5060);
DISPLAY 0.617021 (650 5060);
PAINT PINK (650 5060);
FORCEPROP 2 LAST CDS_LIB mstr_standard
J 0
(650 5050);
DISPLAY 0.787234 (650 5050);
PAINT MONO (650 5050);
DISPLAY INVISIBLE (650 5050);
FORCEPROP 1 LAST BODY_TYPE PLUMBING
J 2
(650 5000);
DISPLAY 1.234043 (650 5000);
PAINT GREEN (650 5000);
DISPLAY INVISIBLE (650 5000);
FORCEPROP 1 LAST HDL_TAP TRUE
J 2
(325 4925);
DISPLAY 1.234043 (325 4925);
PAINT GREEN (325 4925);
DISPLAY INVISIBLE (325 4925);
FORCEPROP 1 LAST PATH I8
J 2
(650 5050);
DISPLAY 0.936170 (650 5050);
PAINT GREEN (650 5050);
DISPLAY INVISIBLE (650 5050);
FORCEADD TAP..6
R 2
(-1750 3000);
FORCEPROP 3 LASTPIN (-1800 3000) SIG_NAME M_J_DQ<27>
J 0
(-1790 3010);
DISPLAY 0.659574 (-1790 3010);
PAINT MONO (-1790 3010);
DISPLAY INVISIBLE (-1790 3010);
FORCEPROP 1 LASTPIN (-1800 3000) BN 27
J 2
(-1750 3010);
DISPLAY 0.617021 (-1750 3010);
PAINT PINK (-1750 3010);
FORCEPROP 2 LAST CDS_LIB mstr_standard
J 2
(-1750 3000);
DISPLAY 0.787234 (-1750 3000);
PAINT MONO (-1750 3000);
DISPLAY INVISIBLE (-1750 3000);
FORCEPROP 1 LAST BODY_TYPE PLUMBING
J 2
(-1750 2950);
DISPLAY 1.234043 (-1750 2950);
PAINT GREEN (-1750 2950);
DISPLAY INVISIBLE (-1750 2950);
FORCEPROP 1 LAST HDL_TAP TRUE
J 2
(-2075 2875);
DISPLAY 1.234043 (-2075 2875);
PAINT GREEN (-2075 2875);
DISPLAY INVISIBLE (-2075 2875);
FORCEPROP 1 LAST PATH I80
J 2
(-1750 3000);
DISPLAY 0.936170 (-1750 3000);
PAINT GREEN (-1750 3000);
DISPLAY INVISIBLE (-1750 3000);
FORCEADD TAP..6
R 2
(-1750 3050);
FORCEPROP 3 LASTPIN (-1800 3050) SIG_NAME M_J_DQ<28>
J 0
(-1790 3060);
DISPLAY 0.659574 (-1790 3060);
PAINT MONO (-1790 3060);
DISPLAY INVISIBLE (-1790 3060);
FORCEPROP 1 LASTPIN (-1800 3050) BN 28
J 2
(-1750 3060);
DISPLAY 0.617021 (-1750 3060);
PAINT PINK (-1750 3060);
FORCEPROP 2 LAST CDS_LIB mstr_standard
J 2
(-1750 3050);
DISPLAY 0.787234 (-1750 3050);
PAINT MONO (-1750 3050);
DISPLAY INVISIBLE (-1750 3050);
FORCEPROP 1 LAST BODY_TYPE PLUMBING
J 2
(-1750 3000);
DISPLAY 1.234043 (-1750 3000);
PAINT GREEN (-1750 3000);
DISPLAY INVISIBLE (-1750 3000);
FORCEPROP 1 LAST HDL_TAP TRUE
J 2
(-2075 2925);
DISPLAY 1.234043 (-2075 2925);
PAINT GREEN (-2075 2925);
DISPLAY INVISIBLE (-2075 2925);
FORCEPROP 1 LAST PATH I81
J 2
(-1750 3050);
DISPLAY 0.936170 (-1750 3050);
PAINT GREEN (-1750 3050);
DISPLAY INVISIBLE (-1750 3050);
FORCEADD TAP..6
R 2
(-1750 2950);
FORCEPROP 3 LASTPIN (-1800 2950) SIG_NAME M_J_DQ<26>
J 0
(-1790 2960);
DISPLAY 0.659574 (-1790 2960);
PAINT MONO (-1790 2960);
DISPLAY INVISIBLE (-1790 2960);
FORCEPROP 1 LASTPIN (-1800 2950) BN 26
J 2
(-1750 2960);
DISPLAY 0.617021 (-1750 2960);
PAINT PINK (-1750 2960);
FORCEPROP 2 LAST CDS_LIB mstr_standard
J 2
(-1750 2950);
DISPLAY 0.787234 (-1750 2950);
PAINT MONO (-1750 2950);
DISPLAY INVISIBLE (-1750 2950);
FORCEPROP 1 LAST BODY_TYPE PLUMBING
J 2
(-1750 2900);
DISPLAY 1.234043 (-1750 2900);
PAINT GREEN (-1750 2900);
DISPLAY INVISIBLE (-1750 2900);
FORCEPROP 1 LAST HDL_TAP TRUE
J 2
(-2075 2825);
DISPLAY 1.234043 (-2075 2825);
PAINT GREEN (-2075 2825);
DISPLAY INVISIBLE (-2075 2825);
FORCEPROP 1 LAST PATH I82
J 2
(-1750 2950);
DISPLAY 0.936170 (-1750 2950);
PAINT GREEN (-1750 2950);
DISPLAY INVISIBLE (-1750 2950);
FORCEADD TAP..6
R 2
(-1750 3100);
FORCEPROP 3 LASTPIN (-1800 3100) SIG_NAME M_J_DQ<29>
J 0
(-1790 3110);
DISPLAY 0.659574 (-1790 3110);
PAINT MONO (-1790 3110);
DISPLAY INVISIBLE (-1790 3110);
FORCEPROP 1 LASTPIN (-1800 3100) BN 29
J 2
(-1750 3110);
DISPLAY 0.617021 (-1750 3110);
PAINT PINK (-1750 3110);
FORCEPROP 2 LAST CDS_LIB mstr_standard
J 2
(-1750 3100);
DISPLAY 0.787234 (-1750 3100);
PAINT MONO (-1750 3100);
DISPLAY INVISIBLE (-1750 3100);
FORCEPROP 1 LAST BODY_TYPE PLUMBING
J 2
(-1750 3050);
DISPLAY 1.234043 (-1750 3050);
PAINT GREEN (-1750 3050);
DISPLAY INVISIBLE (-1750 3050);
FORCEPROP 1 LAST HDL_TAP TRUE
J 2
(-2075 2975);
DISPLAY 1.234043 (-2075 2975);
PAINT GREEN (-2075 2975);
DISPLAY INVISIBLE (-2075 2975);
FORCEPROP 1 LAST PATH I83
J 2
(-1750 3100);
DISPLAY 0.936170 (-1750 3100);
PAINT GREEN (-1750 3100);
DISPLAY INVISIBLE (-1750 3100);
FORCEADD TAP..6
R 2
(-1750 3150);
FORCEPROP 3 LASTPIN (-1800 3150) SIG_NAME M_J_DQ<30>
J 0
(-1790 3160);
DISPLAY 0.659574 (-1790 3160);
PAINT MONO (-1790 3160);
DISPLAY INVISIBLE (-1790 3160);
FORCEPROP 1 LASTPIN (-1800 3150) BN 30
J 2
(-1750 3160);
DISPLAY 0.617021 (-1750 3160);
PAINT PINK (-1750 3160);
FORCEPROP 2 LAST CDS_LIB mstr_standard
J 2
(-1750 3150);
DISPLAY 0.787234 (-1750 3150);
PAINT MONO (-1750 3150);
DISPLAY INVISIBLE (-1750 3150);
FORCEPROP 1 LAST BODY_TYPE PLUMBING
J 2
(-1750 3100);
DISPLAY 1.234043 (-1750 3100);
PAINT GREEN (-1750 3100);
DISPLAY INVISIBLE (-1750 3100);
FORCEPROP 1 LAST HDL_TAP TRUE
J 2
(-2075 3025);
DISPLAY 1.234043 (-2075 3025);
PAINT GREEN (-2075 3025);
DISPLAY INVISIBLE (-2075 3025);
FORCEPROP 1 LAST PATH I84
J 2
(-1750 3150);
DISPLAY 0.936170 (-1750 3150);
PAINT GREEN (-1750 3150);
DISPLAY INVISIBLE (-1750 3150);
FORCEADD TAP..6
R 2
(-1750 2750);
FORCEPROP 3 LASTPIN (-1800 2750) SIG_NAME M_J_DQ<22>
J 0
(-1790 2760);
DISPLAY 0.659574 (-1790 2760);
PAINT MONO (-1790 2760);
DISPLAY INVISIBLE (-1790 2760);
FORCEPROP 1 LASTPIN (-1800 2750) BN 22
J 2
(-1750 2760);
DISPLAY 0.617021 (-1750 2760);
PAINT PINK (-1750 2760);
FORCEPROP 2 LAST CDS_LIB mstr_standard
J 2
(-1750 2750);
DISPLAY 0.787234 (-1750 2750);
PAINT MONO (-1750 2750);
DISPLAY INVISIBLE (-1750 2750);
FORCEPROP 1 LAST BODY_TYPE PLUMBING
J 2
(-1750 2700);
DISPLAY 1.234043 (-1750 2700);
PAINT GREEN (-1750 2700);
DISPLAY INVISIBLE (-1750 2700);
FORCEPROP 1 LAST HDL_TAP TRUE
J 2
(-2075 2625);
DISPLAY 1.234043 (-2075 2625);
PAINT GREEN (-2075 2625);
DISPLAY INVISIBLE (-2075 2625);
FORCEPROP 1 LAST PATH I85
J 2
(-1750 2750);
DISPLAY 0.936170 (-1750 2750);
PAINT GREEN (-1750 2750);
DISPLAY INVISIBLE (-1750 2750);
FORCEADD TAP..6
R 2
(-1750 2800);
FORCEPROP 3 LASTPIN (-1800 2800) SIG_NAME M_J_DQ<23>
J 0
(-1790 2810);
DISPLAY 0.659574 (-1790 2810);
PAINT MONO (-1790 2810);
DISPLAY INVISIBLE (-1790 2810);
FORCEPROP 1 LASTPIN (-1800 2800) BN 23
J 2
(-1750 2810);
DISPLAY 0.617021 (-1750 2810);
PAINT PINK (-1750 2810);
FORCEPROP 2 LAST CDS_LIB mstr_standard
J 2
(-1750 2800);
DISPLAY 0.787234 (-1750 2800);
PAINT MONO (-1750 2800);
DISPLAY INVISIBLE (-1750 2800);
FORCEPROP 1 LAST BODY_TYPE PLUMBING
J 2
(-1750 2750);
DISPLAY 1.234043 (-1750 2750);
PAINT GREEN (-1750 2750);
DISPLAY INVISIBLE (-1750 2750);
FORCEPROP 1 LAST HDL_TAP TRUE
J 2
(-2075 2675);
DISPLAY 1.234043 (-2075 2675);
PAINT GREEN (-2075 2675);
DISPLAY INVISIBLE (-2075 2675);
FORCEPROP 1 LAST PATH I86
J 2
(-1750 2800);
DISPLAY 0.936170 (-1750 2800);
PAINT GREEN (-1750 2800);
DISPLAY INVISIBLE (-1750 2800);
FORCEADD TAP..6
R 2
(-1750 2700);
FORCEPROP 3 LASTPIN (-1800 2700) SIG_NAME M_J_DQ<21>
J 0
(-1790 2710);
DISPLAY 0.659574 (-1790 2710);
PAINT MONO (-1790 2710);
DISPLAY INVISIBLE (-1790 2710);
FORCEPROP 1 LASTPIN (-1800 2700) BN 21
J 2
(-1750 2710);
DISPLAY 0.617021 (-1750 2710);
PAINT PINK (-1750 2710);
FORCEPROP 2 LAST CDS_LIB mstr_standard
J 2
(-1750 2700);
DISPLAY 0.787234 (-1750 2700);
PAINT MONO (-1750 2700);
DISPLAY INVISIBLE (-1750 2700);
FORCEPROP 1 LAST BODY_TYPE PLUMBING
J 2
(-1750 2650);
DISPLAY 1.234043 (-1750 2650);
PAINT GREEN (-1750 2650);
DISPLAY INVISIBLE (-1750 2650);
FORCEPROP 1 LAST HDL_TAP TRUE
J 2
(-2075 2575);
DISPLAY 1.234043 (-2075 2575);
PAINT GREEN (-2075 2575);
DISPLAY INVISIBLE (-2075 2575);
FORCEPROP 1 LAST PATH I87
J 2
(-1750 2700);
DISPLAY 0.936170 (-1750 2700);
PAINT GREEN (-1750 2700);
DISPLAY INVISIBLE (-1750 2700);
FORCEADD TAP..6
R 2
(-1750 2900);
FORCEPROP 3 LASTPIN (-1800 2900) SIG_NAME M_J_DQ<25>
J 0
(-1790 2910);
DISPLAY 0.659574 (-1790 2910);
PAINT MONO (-1790 2910);
DISPLAY INVISIBLE (-1790 2910);
FORCEPROP 1 LASTPIN (-1800 2900) BN 25
J 2
(-1750 2910);
DISPLAY 0.617021 (-1750 2910);
PAINT PINK (-1750 2910);
FORCEPROP 2 LAST CDS_LIB mstr_standard
J 2
(-1750 2900);
DISPLAY 0.787234 (-1750 2900);
PAINT MONO (-1750 2900);
DISPLAY INVISIBLE (-1750 2900);
FORCEPROP 1 LAST BODY_TYPE PLUMBING
J 2
(-1750 2850);
DISPLAY 1.234043 (-1750 2850);
PAINT GREEN (-1750 2850);
DISPLAY INVISIBLE (-1750 2850);
FORCEPROP 1 LAST HDL_TAP TRUE
J 2
(-2075 2775);
DISPLAY 1.234043 (-2075 2775);
PAINT GREEN (-2075 2775);
DISPLAY INVISIBLE (-2075 2775);
FORCEPROP 1 LAST PATH I88
J 2
(-1750 2900);
DISPLAY 0.936170 (-1750 2900);
PAINT GREEN (-1750 2900);
DISPLAY INVISIBLE (-1750 2900);
FORCEADD TAP..6
R 2
(-1750 2850);
FORCEPROP 3 LASTPIN (-1800 2850) SIG_NAME M_J_DQ<24>
J 0
(-1790 2860);
DISPLAY 0.659574 (-1790 2860);
PAINT MONO (-1790 2860);
DISPLAY INVISIBLE (-1790 2860);
FORCEPROP 1 LASTPIN (-1800 2850) BN 24
J 2
(-1750 2860);
DISPLAY 0.617021 (-1750 2860);
PAINT PINK (-1750 2860);
FORCEPROP 2 LAST CDS_LIB mstr_standard
J 2
(-1750 2850);
DISPLAY 0.787234 (-1750 2850);
PAINT MONO (-1750 2850);
DISPLAY INVISIBLE (-1750 2850);
FORCEPROP 1 LAST BODY_TYPE PLUMBING
J 2
(-1750 2800);
DISPLAY 1.234043 (-1750 2800);
PAINT GREEN (-1750 2800);
DISPLAY INVISIBLE (-1750 2800);
FORCEPROP 1 LAST HDL_TAP TRUE
J 2
(-2075 2725);
DISPLAY 1.234043 (-2075 2725);
PAINT GREEN (-2075 2725);
DISPLAY INVISIBLE (-2075 2725);
FORCEPROP 1 LAST PATH I89
J 2
(-1750 2850);
DISPLAY 0.936170 (-1750 2850);
PAINT GREEN (-1750 2850);
DISPLAY INVISIBLE (-1750 2850);
FORCEADD TAP..6
R 2
(650 5150);
FORCEPROP 3 LASTPIN (600 5150) SIG_NAME M_J_DQS_DP<17>
J 0
(610 5160);
DISPLAY 0.659574 (610 5160);
PAINT MONO (610 5160);
DISPLAY INVISIBLE (610 5160);
FORCEPROP 1 LASTPIN (600 5150) BN 17
J 2
(650 5160);
DISPLAY 0.617021 (650 5160);
PAINT PINK (650 5160);
FORCEPROP 2 LAST CDS_LIB mstr_standard
J 2
(650 5150);
DISPLAY 0.787234 (650 5150);
PAINT MONO (650 5150);
DISPLAY INVISIBLE (650 5150);
FORCEPROP 1 LAST BODY_TYPE PLUMBING
J 2
(650 5100);
DISPLAY 1.234043 (650 5100);
PAINT GREEN (650 5100);
DISPLAY INVISIBLE (650 5100);
FORCEPROP 1 LAST HDL_TAP TRUE
J 2
(325 5025);
DISPLAY 1.234043 (325 5025);
PAINT GREEN (325 5025);
DISPLAY INVISIBLE (325 5025);
FORCEPROP 1 LAST PATH I9
J 2
(650 5150);
DISPLAY 0.936170 (650 5150);
PAINT GREEN (650 5150);
DISPLAY INVISIBLE (650 5150);
FORCEADD TAP..6
R 2
(-1750 2450);
FORCEPROP 3 LASTPIN (-1800 2450) SIG_NAME M_J_DQ<16>
J 0
(-1790 2460);
DISPLAY 0.659574 (-1790 2460);
PAINT MONO (-1790 2460);
DISPLAY INVISIBLE (-1790 2460);
FORCEPROP 1 LASTPIN (-1800 2450) BN 16
J 2
(-1750 2460);
DISPLAY 0.617021 (-1750 2460);
PAINT PINK (-1750 2460);
FORCEPROP 2 LAST CDS_LIB mstr_standard
J 2
(-1750 2450);
DISPLAY 0.787234 (-1750 2450);
PAINT MONO (-1750 2450);
DISPLAY INVISIBLE (-1750 2450);
FORCEPROP 1 LAST BODY_TYPE PLUMBING
J 2
(-1750 2400);
DISPLAY 1.234043 (-1750 2400);
PAINT GREEN (-1750 2400);
DISPLAY INVISIBLE (-1750 2400);
FORCEPROP 1 LAST HDL_TAP TRUE
J 2
(-2075 2325);
DISPLAY 1.234043 (-2075 2325);
PAINT GREEN (-2075 2325);
DISPLAY INVISIBLE (-2075 2325);
FORCEPROP 1 LAST PATH I90
J 2
(-1750 2450);
DISPLAY 0.936170 (-1750 2450);
PAINT GREEN (-1750 2450);
DISPLAY INVISIBLE (-1750 2450);
FORCEADD TAP..6
R 2
(-1750 2500);
FORCEPROP 3 LASTPIN (-1800 2500) SIG_NAME M_J_DQ<17>
J 0
(-1790 2510);
DISPLAY 0.659574 (-1790 2510);
PAINT MONO (-1790 2510);
DISPLAY INVISIBLE (-1790 2510);
FORCEPROP 1 LASTPIN (-1800 2500) BN 17
J 2
(-1750 2510);
DISPLAY 0.617021 (-1750 2510);
PAINT PINK (-1750 2510);
FORCEPROP 2 LAST CDS_LIB mstr_standard
J 2
(-1750 2500);
DISPLAY 0.787234 (-1750 2500);
PAINT MONO (-1750 2500);
DISPLAY INVISIBLE (-1750 2500);
FORCEPROP 1 LAST BODY_TYPE PLUMBING
J 2
(-1750 2450);
DISPLAY 1.234043 (-1750 2450);
PAINT GREEN (-1750 2450);
DISPLAY INVISIBLE (-1750 2450);
FORCEPROP 1 LAST HDL_TAP TRUE
J 2
(-2075 2375);
DISPLAY 1.234043 (-2075 2375);
PAINT GREEN (-2075 2375);
DISPLAY INVISIBLE (-2075 2375);
FORCEPROP 1 LAST PATH I91
J 2
(-1750 2500);
DISPLAY 0.936170 (-1750 2500);
PAINT GREEN (-1750 2500);
DISPLAY INVISIBLE (-1750 2500);
FORCEADD TAP..6
R 2
(-1750 2550);
FORCEPROP 3 LASTPIN (-1800 2550) SIG_NAME M_J_DQ<18>
J 0
(-1790 2560);
DISPLAY 0.659574 (-1790 2560);
PAINT MONO (-1790 2560);
DISPLAY INVISIBLE (-1790 2560);
FORCEPROP 1 LASTPIN (-1800 2550) BN 18
J 2
(-1750 2560);
DISPLAY 0.617021 (-1750 2560);
PAINT PINK (-1750 2560);
FORCEPROP 2 LAST CDS_LIB mstr_standard
J 2
(-1750 2550);
DISPLAY 0.787234 (-1750 2550);
PAINT MONO (-1750 2550);
DISPLAY INVISIBLE (-1750 2550);
FORCEPROP 1 LAST BODY_TYPE PLUMBING
J 2
(-1750 2500);
DISPLAY 1.234043 (-1750 2500);
PAINT GREEN (-1750 2500);
DISPLAY INVISIBLE (-1750 2500);
FORCEPROP 1 LAST HDL_TAP TRUE
J 2
(-2075 2425);
DISPLAY 1.234043 (-2075 2425);
PAINT GREEN (-2075 2425);
DISPLAY INVISIBLE (-2075 2425);
FORCEPROP 1 LAST PATH I92
J 2
(-1750 2550);
DISPLAY 0.936170 (-1750 2550);
PAINT GREEN (-1750 2550);
DISPLAY INVISIBLE (-1750 2550);
FORCEADD TAP..6
R 2
(-1750 2600);
FORCEPROP 3 LASTPIN (-1800 2600) SIG_NAME M_J_DQ<19>
J 0
(-1790 2610);
DISPLAY 0.659574 (-1790 2610);
PAINT MONO (-1790 2610);
DISPLAY INVISIBLE (-1790 2610);
FORCEPROP 1 LASTPIN (-1800 2600) BN 19
J 2
(-1750 2610);
DISPLAY 0.617021 (-1750 2610);
PAINT PINK (-1750 2610);
FORCEPROP 2 LAST CDS_LIB mstr_standard
J 2
(-1750 2600);
DISPLAY 0.787234 (-1750 2600);
PAINT MONO (-1750 2600);
DISPLAY INVISIBLE (-1750 2600);
FORCEPROP 1 LAST BODY_TYPE PLUMBING
J 2
(-1750 2550);
DISPLAY 1.234043 (-1750 2550);
PAINT GREEN (-1750 2550);
DISPLAY INVISIBLE (-1750 2550);
FORCEPROP 1 LAST HDL_TAP TRUE
J 2
(-2075 2475);
DISPLAY 1.234043 (-2075 2475);
PAINT GREEN (-2075 2475);
DISPLAY INVISIBLE (-2075 2475);
FORCEPROP 1 LAST PATH I93
J 2
(-1750 2600);
DISPLAY 0.936170 (-1750 2600);
PAINT GREEN (-1750 2600);
DISPLAY INVISIBLE (-1750 2600);
FORCEADD TAP..6
R 2
(-1750 2650);
FORCEPROP 3 LASTPIN (-1800 2650) SIG_NAME M_J_DQ<20>
J 0
(-1790 2660);
DISPLAY 0.659574 (-1790 2660);
PAINT MONO (-1790 2660);
DISPLAY INVISIBLE (-1790 2660);
FORCEPROP 1 LASTPIN (-1800 2650) BN 20
J 2
(-1750 2660);
DISPLAY 0.617021 (-1750 2660);
PAINT PINK (-1750 2660);
FORCEPROP 2 LAST CDS_LIB mstr_standard
J 2
(-1750 2650);
DISPLAY 0.787234 (-1750 2650);
PAINT MONO (-1750 2650);
DISPLAY INVISIBLE (-1750 2650);
FORCEPROP 1 LAST BODY_TYPE PLUMBING
J 2
(-1750 2600);
DISPLAY 1.234043 (-1750 2600);
PAINT GREEN (-1750 2600);
DISPLAY INVISIBLE (-1750 2600);
FORCEPROP 1 LAST HDL_TAP TRUE
J 2
(-2075 2525);
DISPLAY 1.234043 (-2075 2525);
PAINT GREEN (-2075 2525);
DISPLAY INVISIBLE (-2075 2525);
FORCEPROP 1 LAST PATH I94
J 2
(-1750 2650);
DISPLAY 0.936170 (-1750 2650);
PAINT GREEN (-1750 2650);
DISPLAY INVISIBLE (-1750 2650);
FORCEADD TAP..6
R 2
(-1750 2200);
FORCEPROP 3 LASTPIN (-1800 2200) SIG_NAME M_J_DQ<11>
J 0
(-1790 2210);
DISPLAY 0.659574 (-1790 2210);
PAINT MONO (-1790 2210);
DISPLAY INVISIBLE (-1790 2210);
FORCEPROP 1 LASTPIN (-1800 2200) BN 11
J 2
(-1750 2210);
DISPLAY 0.617021 (-1750 2210);
PAINT PINK (-1750 2210);
FORCEPROP 2 LAST CDS_LIB mstr_standard
J 2
(-1750 2200);
DISPLAY 0.787234 (-1750 2200);
PAINT MONO (-1750 2200);
DISPLAY INVISIBLE (-1750 2200);
FORCEPROP 1 LAST BODY_TYPE PLUMBING
J 2
(-1750 2150);
DISPLAY 1.234043 (-1750 2150);
PAINT GREEN (-1750 2150);
DISPLAY INVISIBLE (-1750 2150);
FORCEPROP 1 LAST HDL_TAP TRUE
J 2
(-2075 2075);
DISPLAY 1.234043 (-2075 2075);
PAINT GREEN (-2075 2075);
DISPLAY INVISIBLE (-2075 2075);
FORCEPROP 1 LAST PATH I95
J 2
(-1750 2200);
DISPLAY 0.936170 (-1750 2200);
PAINT GREEN (-1750 2200);
DISPLAY INVISIBLE (-1750 2200);
FORCEADD TAP..6
R 2
(-1750 2300);
FORCEPROP 3 LASTPIN (-1800 2300) SIG_NAME M_J_DQ<13>
J 0
(-1790 2310);
DISPLAY 0.659574 (-1790 2310);
PAINT MONO (-1790 2310);
DISPLAY INVISIBLE (-1790 2310);
FORCEPROP 1 LASTPIN (-1800 2300) BN 13
J 2
(-1750 2310);
DISPLAY 0.617021 (-1750 2310);
PAINT PINK (-1750 2310);
FORCEPROP 2 LAST CDS_LIB mstr_standard
J 2
(-1750 2300);
DISPLAY 0.787234 (-1750 2300);
PAINT MONO (-1750 2300);
DISPLAY INVISIBLE (-1750 2300);
FORCEPROP 1 LAST BODY_TYPE PLUMBING
J 2
(-1750 2250);
DISPLAY 1.234043 (-1750 2250);
PAINT GREEN (-1750 2250);
DISPLAY INVISIBLE (-1750 2250);
FORCEPROP 1 LAST HDL_TAP TRUE
J 2
(-2075 2175);
DISPLAY 1.234043 (-2075 2175);
PAINT GREEN (-2075 2175);
DISPLAY INVISIBLE (-2075 2175);
FORCEPROP 1 LAST PATH I96
J 2
(-1750 2300);
DISPLAY 0.936170 (-1750 2300);
PAINT GREEN (-1750 2300);
DISPLAY INVISIBLE (-1750 2300);
FORCEADD TAP..6
R 2
(-1750 2250);
FORCEPROP 3 LASTPIN (-1800 2250) SIG_NAME M_J_DQ<12>
J 0
(-1790 2260);
DISPLAY 0.659574 (-1790 2260);
PAINT MONO (-1790 2260);
DISPLAY INVISIBLE (-1790 2260);
FORCEPROP 1 LASTPIN (-1800 2250) BN 12
J 2
(-1750 2260);
DISPLAY 0.617021 (-1750 2260);
PAINT PINK (-1750 2260);
FORCEPROP 2 LAST CDS_LIB mstr_standard
J 2
(-1750 2250);
DISPLAY 0.787234 (-1750 2250);
PAINT MONO (-1750 2250);
DISPLAY INVISIBLE (-1750 2250);
FORCEPROP 1 LAST BODY_TYPE PLUMBING
J 2
(-1750 2200);
DISPLAY 1.234043 (-1750 2200);
PAINT GREEN (-1750 2200);
DISPLAY INVISIBLE (-1750 2200);
FORCEPROP 1 LAST HDL_TAP TRUE
J 2
(-2075 2125);
DISPLAY 1.234043 (-2075 2125);
PAINT GREEN (-2075 2125);
DISPLAY INVISIBLE (-2075 2125);
FORCEPROP 1 LAST PATH I97
J 2
(-1750 2250);
DISPLAY 0.936170 (-1750 2250);
PAINT GREEN (-1750 2250);
DISPLAY INVISIBLE (-1750 2250);
FORCEADD TAP..6
R 2
(-1750 2350);
FORCEPROP 3 LASTPIN (-1800 2350) SIG_NAME M_J_DQ<14>
J 0
(-1790 2360);
DISPLAY 0.659574 (-1790 2360);
PAINT MONO (-1790 2360);
DISPLAY INVISIBLE (-1790 2360);
FORCEPROP 1 LASTPIN (-1800 2350) BN 14
J 2
(-1750 2360);
DISPLAY 0.617021 (-1750 2360);
PAINT PINK (-1750 2360);
FORCEPROP 2 LAST CDS_LIB mstr_standard
J 2
(-1750 2350);
DISPLAY 0.787234 (-1750 2350);
PAINT MONO (-1750 2350);
DISPLAY INVISIBLE (-1750 2350);
FORCEPROP 1 LAST BODY_TYPE PLUMBING
J 2
(-1750 2300);
DISPLAY 1.234043 (-1750 2300);
PAINT GREEN (-1750 2300);
DISPLAY INVISIBLE (-1750 2300);
FORCEPROP 1 LAST HDL_TAP TRUE
J 2
(-2075 2225);
DISPLAY 1.234043 (-2075 2225);
PAINT GREEN (-2075 2225);
DISPLAY INVISIBLE (-2075 2225);
FORCEPROP 1 LAST PATH I98
J 2
(-1750 2350);
DISPLAY 0.936170 (-1750 2350);
PAINT GREEN (-1750 2350);
DISPLAY INVISIBLE (-1750 2350);
FORCEADD TAP..6
R 2
(-1750 2400);
FORCEPROP 3 LASTPIN (-1800 2400) SIG_NAME M_J_DQ<15>
J 0
(-1790 2410);
DISPLAY 0.659574 (-1790 2410);
PAINT MONO (-1790 2410);
DISPLAY INVISIBLE (-1790 2410);
FORCEPROP 1 LASTPIN (-1800 2400) BN 15
J 2
(-1750 2410);
DISPLAY 0.617021 (-1750 2410);
PAINT PINK (-1750 2410);
FORCEPROP 2 LAST CDS_LIB mstr_standard
J 2
(-1750 2400);
DISPLAY 0.787234 (-1750 2400);
PAINT MONO (-1750 2400);
DISPLAY INVISIBLE (-1750 2400);
FORCEPROP 1 LAST BODY_TYPE PLUMBING
J 2
(-1750 2350);
DISPLAY 1.234043 (-1750 2350);
PAINT GREEN (-1750 2350);
DISPLAY INVISIBLE (-1750 2350);
FORCEPROP 1 LAST HDL_TAP TRUE
J 2
(-2075 2275);
DISPLAY 1.234043 (-2075 2275);
PAINT GREEN (-2075 2275);
DISPLAY INVISIBLE (-2075 2275);
FORCEPROP 1 LAST PATH I99
J 2
(-1750 2400);
DISPLAY 0.936170 (-1750 2400);
PAINT GREEN (-1750 2400);
DISPLAY INVISIBLE (-1750 2400);
FORCEADD BOM_NOTE..1
(-5025 5275);
FORCEPROP 0 LAST L1 UNSTUFF FOR SKU B
J 0
(-5175 5175);
DISPLAY 1.063830 (-5175 5175);
PAINT WHITE (-5175 5175);
FORCEPROP 2 LAST BOM_COST SB
J 0
(-5175 5250);
DISPLAY 1.361702 (-5175 5250);
PAINT ORANGE (-5175 5250);
DISPLAY INVISIBLE (-5175 5250);
FORCEPROP 2 LAST CDS_LIB mstr_symbols
J 0
(-5025 5275);
PAINT ORANGE (-5025 5275);
DISPLAY INVISIBLE (-5025 5275);
FORCEPROP 1 LAST COMMENT_BODY TRUE
J 0
(-5000 5375);
DISPLAY 1.319149 (-5000 5375);
PAINT ORANGE (-5000 5375);
DISPLAY INVISIBLE (-5000 5375);
FORCEPROP 2 LAST ROOM SB_HEADERS
J 0
(-5175 5250);
DISPLAY 1.361702 (-5175 5250);
PAINT ORANGE (-5175 5250);
DISPLAY INVISIBLE (-5175 5250);
FORCEADD INTEL_CORP_BPAGE..1
(2650 500);
FORCEPROP 1 LAST CDS_CON_LAST_MODIFIED Tue Dec 01 11:51:43 2015
J 0
(1225 825);
DISPLAY 0.787234 (1225 825);
PAINT ORANGE (1225 825);
DISPLAY INVISIBLE (1225 825);
FORCEPROP 1 LAST CUSTOM_TXT_CDS <CURRENT_DESIGN_SHEET> OF <TOTAL_DESIGN_SHEETS>
J 0
(2150 525);
PAINT GREEN (2150 525);
FORCEPROP 1 LAST CUSTOM_TXT_CDS <CON_LAST_MODIFIED>
J 0
(725 850);
PAINT GREEN (725 850);
FORCEPROP 2 LAST CUSTOM_TXT_CDS <XR_PAGE_TITLE>
J 0
(-5240 5750);
DISPLAY 0.638298 (-5240 5750);
PAINT PINK (-5240 5750);
DISPLAY INVISIBLE (-5240 5750);
FORCEPROP 1 LAST SCH_ADDRESS3 Santa Clara, CA 95052-8119
J 0
(-1325 525);
DISPLAY 0.617021 (-1325 525);
PAINT GREEN (-1325 525);
FORCEPROP 1 LAST SCH_ADDRESS2 P.O. BOX 58119
J 0
(-1325 575);
DISPLAY 0.617021 (-1325 575);
PAINT GREEN (-1325 575);
FORCEPROP 1 LAST SCH_ADDRESS1 2200 Mission College Blvd.
J 0
(-1325 625);
DISPLAY 0.617021 (-1325 625);
PAINT GREEN (-1325 625);
FORCEPROP 1 LAST SCH_TITLE CPU1 DDR4 CH J DIMM1
J 0
(-5300 550);
DISPLAY 1.212766 (-5300 550);
PAINT WHITE (-5300 550);
FORCEPROP 1 LAST SCH_NUMBER H4694802
J 0
(1350 650);
DISPLAY 1.212766 (1350 650);
PAINT YELLOW (1350 650);
FORCEPROP 1 LAST SCH_DEPT BESD
J 1
(-1800 600);
DISPLAY 1.212766 (-1800 600);
PAINT YELLOW (-1800 600);
FORCEPROP 1 LAST SCH_REV 2.420
J 0
(2400 650);
DISPLAY 0.978723 (2400 650);
PAINT YELLOW (2400 650);
FORCEPROP 2 LAST CDS_LIB mstr_symbols
J 0
(2650 500);
DISPLAY 0.787234 (2650 500);
PAINT MONO (2650 500);
DISPLAY INVISIBLE (2650 500);
FORCEPROP 2 LAST PAGE_BORDER TRUE
J 0
(-5240 5750);
DISPLAY 0.680851 (-5240 5750);
PAINT PINK (-5240 5750);
DISPLAY INVISIBLE (-5240 5750);
FORCEPROP 1 LAST COMMENT_BODY TRUE
J 0
(2660 510);
DISPLAY 0.382979 (2660 510);
PAINT GREEN (2660 510);
DISPLAY INVISIBLE (2660 510);
FORCEPROP 2 LAST CDS_XR_PAGE_TITLE CR-82 : @BASEBOARD_FAB2_LIB.BASEBOARD_FAB2(SCH_1):PAGE82
J 0
(-5240 5750);
DISPLAY 0.638298 (-5240 5750);
PAINT PINK (-5240 5750);
DISPLAY INVISIBLE (-5240 5750);
WIRE 17 -1 (700 5175)(700 5200);
WIRE 17 -1 (700 5075)(700 5175);
WIRE 17 -1 (1500 5200)(700 5200);
FORCEPROP 2 LAST SIG_NAME M_J_DQS_DP<17:0>
J 0
(950 5210);
DISPLAY 0.617021 (950 5210);
PAINT ORANGE (950 5210);
WIRE 17 -1 (700 4375)(700 4475);
WIRE 17 -1 (700 4275)(700 4375);
WIRE 17 -1 (700 4475)(700 4575);
WIRE 17 -1 (700 4575)(700 4675);
WIRE 17 -1 (700 4175)(700 4275);
WIRE 17 -1 (700 4075)(700 4175);
WIRE 17 -1 (700 4675)(700 4775);
WIRE 17 -1 (700 4775)(700 4875);
WIRE 17 -1 (700 3975)(700 4075);
WIRE 17 -1 (700 3875)(700 3975);
WIRE 17 -1 (700 4875)(700 4975);
WIRE 17 -1 (700 4975)(700 5075);
WIRE 17 -1 (700 3775)(700 3875);
WIRE 17 -1 (700 3675)(700 3775);
WIRE 17 -1 (700 3575)(700 3675);
WIRE 17 -1 (700 3475)(700 3575);
WIRE 17 -1 (900 4325)(900 4425);
WIRE 17 -1 (900 4225)(900 4325);
WIRE 17 -1 (900 4425)(900 4525);
WIRE 17 -1 (900 4525)(900 4625);
WIRE 17 -1 (900 4125)(900 4225);
WIRE 17 -1 (900 4025)(900 4125);
WIRE 17 -1 (900 4625)(900 4725);
WIRE 17 -1 (900 4725)(900 4825);
WIRE 17 -1 (900 3925)(900 4025);
WIRE 17 -1 (900 3825)(900 3925);
WIRE 17 -1 (900 4825)(900 4925);
WIRE 17 -1 (900 4925)(900 5025);
WIRE 17 -1 (900 3725)(900 3825);
WIRE 17 -1 (900 3625)(900 3725);
WIRE 17 -1 (900 5025)(900 5125);
WIRE 17 -1 (900 5125)(900 5150);
WIRE 17 -1 (900 3525)(900 3625);
WIRE 17 -1 (900 3425)(900 3525);
WIRE 17 -1 (1500 5150)(900 5150);
FORCEPROP 2 LAST SIG_NAME M_J_DQS_DN<17:0>
J 0
(950 5160);
DISPLAY 0.617021 (950 5160);
PAINT ORANGE (950 5160);
WIRE 17 -1 (-1700 4675)(-1700 4725);
WIRE 17 -1 (-1700 4625)(-1700 4675);
WIRE 17 -1 (-1700 4725)(-1700 4775);
WIRE 17 -1 (-1700 4775)(-1700 4825);
WIRE 17 -1 (-1700 4575)(-1700 4625);
WIRE 17 -1 (-1700 4525)(-1700 4575);
WIRE 17 -1 (-1700 4825)(-1700 4850);
WIRE 17 -1 (-1250 4850)(-1700 4850);
FORCEPROP 2 LAST SIG_NAME M_J_DQ<63:0>
J 0
(-1660 4860);
DISPLAY 0.617021 (-1660 4860);
PAINT ORANGE (-1660 4860);
WIRE 17 -1 (-1700 4475)(-1700 4525);
WIRE 17 -1 (-1700 4425)(-1700 4475);
WIRE 17 -1 (-1700 4375)(-1700 4425);
WIRE 17 -1 (-1700 4325)(-1700 4375);
WIRE 17 -1 (-1700 4275)(-1700 4325);
WIRE 17 -1 (-1700 4225)(-1700 4275);
WIRE 17 -1 (-1700 4175)(-1700 4225);
WIRE 17 -1 (-1700 4125)(-1700 4175);
WIRE 17 -1 (-1700 4075)(-1700 4125);
WIRE 17 -1 (-1700 4025)(-1700 4075);
WIRE 17 -1 (-1700 3975)(-1700 4025);
WIRE 17 -1 (-1700 3925)(-1700 3975);
WIRE 17 -1 (-1700 3875)(-1700 3925);
WIRE 17 -1 (-1700 3825)(-1700 3875);
WIRE 17 -1 (-1700 3775)(-1700 3825);
WIRE 17 -1 (-1700 3725)(-1700 3775);
WIRE 17 -1 (-1700 3675)(-1700 3725);
WIRE 17 -1 (-1700 3625)(-1700 3675);
WIRE 17 -1 (-1700 3575)(-1700 3625);
WIRE 17 -1 (-1700 3525)(-1700 3575);
WIRE 17 -1 (-1700 3475)(-1700 3525);
WIRE 17 -1 (-1700 3425)(-1700 3475);
WIRE 17 -1 (-1700 3375)(-1700 3425);
WIRE 17 -1 (-3300 4775)(-3300 4825);
WIRE 17 -1 (-3300 4725)(-3300 4775);
WIRE 17 -1 (-3300 4825)(-3300 4850);
WIRE 17 -1 (-3850 4850)(-3300 4850);
FORCEPROP 2 LAST SIG_NAME M_J_MA<17:0>
J 0
(-3800 4860);
DISPLAY 0.617021 (-3800 4860);
PAINT ORANGE (-3800 4860);
WIRE 17 -1 (-3300 4675)(-3300 4725);
WIRE 17 -1 (-3300 4625)(-3300 4675);
WIRE 17 -1 (-3300 4575)(-3300 4625);
WIRE 17 -1 (-3300 4525)(-3300 4575);
WIRE 17 -1 (-3300 4475)(-3300 4525);
WIRE 17 -1 (-3300 4425)(-3300 4475);
WIRE 17 -1 (-3300 4375)(-3300 4425);
WIRE 17 -1 (-3300 4325)(-3300 4375);
WIRE 17 -1 (-3300 4275)(-3300 4325);
WIRE 17 -1 (-3300 4225)(-3300 4275);
WIRE 17 -1 (-3300 4175)(-3300 4225);
WIRE 17 -1 (-3300 4125)(-3300 4175);
WIRE 17 -1 (-3300 4075)(-3300 4125);
WIRE 17 -1 (-3300 4025)(-3300 4075);
WIRE 17 -1 (-3300 3975)(-3300 4025);
WIRE 17 -1 (-1700 3325)(-1700 3375);
WIRE 17 -1 (-1700 3275)(-1700 3325);
WIRE 17 -1 (-1700 3225)(-1700 3275);
WIRE 17 -1 (-1700 3175)(-1700 3225);
WIRE 17 -1 (-1700 3125)(-1700 3175);
WIRE 17 -1 (-1700 3075)(-1700 3125);
WIRE 17 -1 (-1700 3025)(-1700 3075);
WIRE 17 -1 (-1700 2975)(-1700 3025);
WIRE 17 -1 (-1700 2925)(-1700 2975);
WIRE 17 -1 (-1700 2875)(-1700 2925);
WIRE 17 -1 (-1700 2825)(-1700 2875);
WIRE 17 -1 (-1700 2775)(-1700 2825);
WIRE 17 -1 (-1700 2725)(-1700 2775);
WIRE 17 -1 (-1700 2675)(-1700 2725);
WIRE 17 -1 (-1700 2625)(-1700 2675);
WIRE 17 -1 (-1700 2575)(-1700 2625);
WIRE 17 -1 (-1700 2525)(-1700 2575);
WIRE 17 -1 (-1700 2475)(-1700 2525);
WIRE 17 -1 (-1700 2425)(-1700 2475);
WIRE 17 -1 (-1700 2375)(-1700 2425);
WIRE 17 -1 (-1700 2325)(-1700 2375);
WIRE 17 -1 (-1700 2275)(-1700 2325);
WIRE 17 -1 (-1700 2225)(-1700 2275);
WIRE 17 -1 (-1700 2175)(-1700 2225);
WIRE 17 -1 (-1700 2125)(-1700 2175);
WIRE 17 -1 (-1700 2075)(-1700 2125);
WIRE 17 -1 (-1700 2025)(-1700 2075);
WIRE 17 -1 (-1700 1975)(-1700 2025);
WIRE 17 -1 (-1700 1925)(-1700 1975);
WIRE 17 -1 (-1700 1875)(-1700 1925);
WIRE 17 -1 (-1700 1825)(-1700 1875);
WIRE 17 -1 (-1700 1775)(-1700 1825);
WIRE 17 -1 (-1700 1725)(-1700 1775);
WIRE 17 -1 (-1700 1675)(-1700 1725);
WIRE 17 -1 (-3500 3575)(-3500 3600);
WIRE 17 -1 (-3500 3575)(-3500 3475);
WIRE 17 -1 (-3500 3600)(-3850 3600);
FORCEPROP 2 LAST SIG_NAME M_J_CLK_DN<3:0>
J 0
(-3825 3610);
DISPLAY 0.617021 (-3825 3610);
PAINT ORANGE (-3825 3610);
WIRE 17 -1 (-3350 3175)(-3350 3225);
WIRE 17 -1 (-3350 3225)(-3350 3275);
WIRE 17 -1 (-3350 3275)(-3350 3325);
WIRE 17 -1 (-3350 3325)(-3350 3350);
WIRE 17 -1 (-3350 3350)(-3850 3350);
FORCEPROP 2 LAST SIG_NAME M_J_CS_N<7:0>
J 0
(-3825 3360);
DISPLAY 0.617021 (-3825 3360);
PAINT ORANGE (-3825 3360);
WIRE 17 -1 (-3350 3025)(-3350 3075);
WIRE 17 -1 (-3350 3075)(-3350 3100);
WIRE 17 -1 (-3350 3100)(-3850 3100);
FORCEPROP 2 LAST SIG_NAME M_J_CKE<3:0>
J 0
(-3825 3110);
DISPLAY 0.617021 (-3825 3110);
PAINT ORANGE (-3825 3110);
WIRE 17 -1 (-3350 2925)(-3350 2950);
WIRE 17 -1 (-3350 2875)(-3350 2925);
WIRE 17 -1 (-3350 2950)(-3850 2950);
FORCEPROP 2 LAST SIG_NAME M_J_ODT<3:0>
J 0
(-3825 2960);
DISPLAY 0.617021 (-3825 2960);
PAINT ORANGE (-3825 2960);
WIRE 17 -1 (-3350 2775)(-3350 2800);
WIRE 17 -1 (-3350 2725)(-3350 2775);
WIRE 17 -1 (-3350 2800)(-3850 2800);
FORCEPROP 2 LAST SIG_NAME M_J_ECC<7:0>
J 0
(-3825 2810);
DISPLAY 0.617021 (-3825 2810);
PAINT ORANGE (-3825 2810);
WIRE 17 -1 (-3300 3825)(-3300 3875);
WIRE 17 -1 (-3300 3900)(-3300 3875);
WIRE 17 -1 (-3300 3900)(-3850 3900);
FORCEPROP 2 LAST SIG_NAME M_J_BA<1:0>
J 0
(-3825 3910);
DISPLAY 0.617021 (-3825 3910);
PAINT ORANGE (-3825 3910);
WIRE 17 -1 (-3300 3775)(-3300 3800);
WIRE 17 -1 (-3300 3725)(-3300 3775);
WIRE 17 -1 (-3300 3800)(-3850 3800);
FORCEPROP 2 LAST SIG_NAME M_J_BG<1:0>
J 0
(-3825 3810);
DISPLAY 0.617021 (-3825 3810);
PAINT ORANGE (-3825 3810);
WIRE 17 -1 (-3300 3625)(-3300 3650);
WIRE 17 -1 (-3300 3525)(-3300 3625);
WIRE 17 -1 (-3300 3650)(-3850 3650);
FORCEPROP 2 LAST SIG_NAME M_J_CLK_DP<3:0>
J 0
(-3825 3660);
DISPLAY 0.617021 (-3825 3660);
PAINT ORANGE (-3825 3660);
WIRE 17 -1 (-3350 2425)(-3350 2475);
WIRE 17 -1 (-3350 2475)(-3350 2525);
WIRE 17 -1 (-3350 2525)(-3350 2575);
WIRE 17 -1 (-3350 2575)(-3350 2625);
WIRE 17 -1 (-3350 2625)(-3350 2675);
WIRE 17 -1 (-3350 2675)(-3350 2725);
WIRE 16 -1 (-1000 1200)(-850 1200);
WIRE 16 -1 (-1000 1200)(-1000 1250);
WIRE 16 -1 (-1000 1250)(-1000 1300);
WIRE 16 -1 (-1000 1250)(-850 1250);
WIRE 16 -1 (-1000 1300)(-850 1300);
WIRE 16 -1 (-1000 1300)(-1000 1350);
WIRE 16 -1 (-1000 1350)(-850 1350);
WIRE 16 -1 (-1000 1350)(-1000 1400);
WIRE 16 -1 (-1000 1400)(-850 1400);
WIRE 16 -1 (-1000 1400)(-1000 1450);
WIRE 16 -1 (-1000 1450)(-850 1450);
WIRE 16 -1 (-1000 1450)(-1000 1500);
WIRE 16 -1 (-1000 1500)(-1000 1550);
WIRE 16 -1 (-1000 1500)(-850 1500);
WIRE 16 -1 (-1000 1550)(-850 1550);
WIRE 16 -1 (-1000 1550)(-1000 1600);
WIRE 16 -1 (-1000 1600)(-850 1600);
WIRE 16 -1 (-1000 1600)(-1000 1650);
WIRE 16 -1 (-1000 1650)(-850 1650);
WIRE 16 -1 (-1000 1650)(-1000 1700);
WIRE 16 -1 (-1000 1700)(-850 1700);
WIRE 16 -1 (-1000 1700)(-1000 1750);
WIRE 16 -1 (-1000 1750)(-1000 1800);
WIRE 16 -1 (-1000 1750)(-850 1750);
WIRE 16 -1 (-1000 1800)(-850 1800);
WIRE 16 -1 (-1000 1800)(-1000 1850);
WIRE 16 -1 (-1000 1850)(-850 1850);
WIRE 16 -1 (-1000 1850)(-1000 1900);
WIRE 16 -1 (-1000 1900)(-850 1900);
WIRE 16 -1 (-1000 1900)(-1000 1950);
WIRE 16 -1 (-1000 1950)(-850 1950);
WIRE 16 -1 (-1000 1950)(-1000 2000);
WIRE 16 -1 (-1000 2000)(-1000 2050);
WIRE 16 -1 (-1000 2000)(-850 2000);
WIRE 16 -1 (-1000 2050)(-850 2050);
WIRE 16 -1 (-1000 2050)(-1000 2100);
WIRE 16 -1 (-1000 2100)(-850 2100);
WIRE 16 -1 (-1000 2100)(-1000 2150);
WIRE 16 -1 (-1000 2150)(-850 2150);
WIRE 16 -1 (-1000 2150)(-1000 2200);
WIRE 16 -1 (-1000 2200)(-850 2200);
WIRE 16 -1 (-1000 2200)(-1000 2250);
WIRE 16 -1 (-1000 2250)(-850 2250);
WIRE 16 -1 (-1000 2250)(-1000 2300);
WIRE 16 -1 (-1000 2300)(-1000 2350);
WIRE 16 -1 (-1000 2300)(-850 2300);
WIRE 16 -1 (-1000 2350)(-850 2350);
WIRE 16 -1 (-1000 2350)(-1000 2400);
WIRE 16 -1 (-1000 2400)(-850 2400);
WIRE 16 -1 (-1000 2400)(-1000 2450);
WIRE 16 -1 (-1000 2450)(-850 2450);
WIRE 16 -1 (-1400 2450)(-1000 2450);
WIRE 16 -1 (-1400 2525)(-1400 2450);
WIRE 16 -1 (-1000 2550)(-1000 2600);
WIRE 16 -1 (-1000 2550)(-850 2550);
WIRE 16 -1 (-1000 2600)(-850 2600);
WIRE 16 -1 (-1200 2600)(-1000 2600);
WIRE 16 -1 (-1200 2700)(-1200 2600);
WIRE 16 -1 (2450 3450)(2450 3500);
WIRE 16 -1 (2450 3400)(2450 3450);
WIRE 16 -1 (2450 3450)(2250 3450);
WIRE 16 -1 (2450 3500)(2250 3500);
WIRE 16 -1 (2450 3350)(2450 3400);
WIRE 16 -1 (2450 3400)(2250 3400);
WIRE 16 -1 (2450 3300)(2450 3350);
WIRE 16 -1 (2450 3350)(2250 3350);
WIRE 16 -1 (2450 3250)(2450 3300);
WIRE 16 -1 (2450 3300)(2250 3300);
WIRE 16 -1 (2450 3200)(2450 3250);
WIRE 16 -1 (2450 3250)(2250 3250);
WIRE 16 -1 (2450 3150)(2450 3200);
WIRE 16 -1 (2450 3200)(2250 3200);
WIRE 16 -1 (2450 3100)(2450 3150);
WIRE 16 -1 (2450 3150)(2250 3150);
WIRE 16 -1 (2450 3100)(2250 3100);
WIRE 16 -1 (2450 3050)(2450 3100);
WIRE 16 -1 (2450 3000)(2450 3050);
WIRE 16 -1 (2450 3050)(2250 3050);
WIRE 16 -1 (2450 2950)(2450 3000);
WIRE 16 -1 (2450 3000)(2250 3000);
WIRE 16 -1 (2450 2900)(2450 2950);
WIRE 16 -1 (2450 2950)(2250 2950);
WIRE 16 -1 (2450 2850)(2450 2900);
WIRE 16 -1 (2450 2900)(2250 2900);
WIRE 16 -1 (2450 2800)(2450 2850);
WIRE 16 -1 (2450 2850)(2250 2850);
WIRE 16 -1 (2450 2750)(2450 2800);
WIRE 16 -1 (2450 2800)(2250 2800);
WIRE 16 -1 (2450 2700)(2450 2750);
WIRE 16 -1 (2450 2750)(2250 2750);
WIRE 16 -1 (2450 2650)(2450 2700);
WIRE 16 -1 (2450 2700)(2250 2700);
WIRE 16 -1 (2450 2600)(2450 2650);
WIRE 16 -1 (2450 2650)(2250 2650);
WIRE 16 -1 (2450 2600)(2250 2600);
WIRE 16 -1 (2450 2550)(2450 2600);
WIRE 16 -1 (2450 2500)(2450 2550);
WIRE 16 -1 (2450 2550)(2250 2550);
WIRE 16 -1 (2450 2450)(2450 2500);
WIRE 16 -1 (2450 2500)(2250 2500);
WIRE 16 -1 (2450 2400)(2450 2450);
WIRE 16 -1 (2450 2450)(2250 2450);
WIRE 16 -1 (2450 2350)(2450 2400);
WIRE 16 -1 (2450 2400)(2250 2400);
WIRE 16 -1 (2450 2300)(2450 2350);
WIRE 16 -1 (2450 2350)(2250 2350);
WIRE 16 -1 (2450 2250)(2450 2300);
WIRE 16 -1 (2450 2300)(2250 2300);
WIRE 16 -1 (2450 2200)(2450 2250);
WIRE 16 -1 (2450 2250)(2250 2250);
WIRE 16 -1 (2450 2150)(2450 2200);
WIRE 16 -1 (2450 2200)(2250 2200);
WIRE 16 -1 (2450 2100)(2450 2150);
WIRE 16 -1 (2450 2150)(2250 2150);
WIRE 16 -1 (2450 2050)(2450 2100);
WIRE 16 -1 (2450 2100)(2250 2100);
WIRE 16 -1 (2450 2050)(2250 2050);
WIRE 16 -1 (2450 2000)(2450 2050);
WIRE 16 -1 (2450 1950)(2450 2000);
WIRE 16 -1 (2450 2000)(2250 2000);
WIRE 16 -1 (2450 1900)(2450 1950);
WIRE 16 -1 (2450 1950)(2250 1950);
WIRE 16 -1 (2450 1850)(2450 1900);
WIRE 16 -1 (2450 1900)(2250 1900);
WIRE 16 -1 (2450 1800)(2450 1850);
WIRE 16 -1 (2450 1850)(2250 1850);
WIRE 16 -1 (2450 1750)(2450 1800);
WIRE 16 -1 (2450 1800)(2250 1800);
WIRE 16 -1 (2450 1700)(2450 1750);
WIRE 16 -1 (2450 1750)(2250 1750);
WIRE 16 -1 (2450 1650)(2450 1700);
WIRE 16 -1 (2450 1700)(2250 1700);
WIRE 16 -1 (2450 1600)(2450 1650);
WIRE 16 -1 (2450 1650)(2250 1650);
WIRE 16 -1 (2450 1550)(2450 1600);
WIRE 16 -1 (2450 1600)(2250 1600);
WIRE 16 -1 (2450 1550)(2250 1550);
WIRE 16 -1 (2450 1500)(2450 1550);
WIRE 16 -1 (2450 1450)(2450 1500);
WIRE 16 -1 (2450 1500)(2250 1500);
WIRE 16 -1 (2450 1400)(2450 1450);
WIRE 16 -1 (2450 1450)(2250 1450);
WIRE 16 -1 (2450 1350)(2450 1400);
WIRE 16 -1 (2450 1400)(2250 1400);
WIRE 16 -1 (2450 1300)(2450 1350);
WIRE 16 -1 (2450 1350)(2250 1350);
WIRE 16 -1 (2450 1250)(2450 1300);
WIRE 16 -1 (2450 1300)(2250 1300);
WIRE 16 -1 (2450 1200)(2450 1250);
WIRE 16 -1 (2450 1250)(2250 1250);
WIRE 16 -1 (2450 1100)(2450 1200);
WIRE 16 -1 (2450 1200)(2250 1200);
WIRE 16 -1 (-4500 1350)(-4500 1200);
WIRE 16 -1 (-1050 2700)(-850 2700);
WIRE 16 -1 (-1050 2750)(-1050 2700);
WIRE 16 -1 (-1050 2750)(-850 2750);
WIRE 16 -1 (-1050 2800)(-1050 2750);
WIRE 16 -1 (-1050 2800)(-850 2800);
WIRE 16 -1 (-1050 2850)(-1050 2800);
WIRE 16 -1 (-1050 2850)(-850 2850);
WIRE 16 -1 (-1050 2900)(-1050 2850);
WIRE 16 -1 (-1050 2900)(-850 2900);
WIRE 16 -1 (-1050 2975)(-1050 2900);
WIRE 16 -1 (-3150 1850)(-3000 1850);
WIRE 16 -1 (-3150 1850)(-3150 1950);
WIRE 16 -1 (-3150 1950)(-3000 1950);
WIRE 16 -1 (-3150 2000)(-3150 1950);
WIRE 16 -1 (-3000 2000)(-3150 2000);
WIRE 16 -1 (-3150 2000)(-5200 2000);
WIRE 16 -1 (-5200 2100)(-5200 2000);
WIRE 16 -1 (-3000 1900)(-5200 1900);
WIRE 16 -1 (-5200 1900)(-5200 1850);
WIRE 16 -1 (150 2850)(350 2850);
WIRE 16 -1 (350 2850)(350 2900);
WIRE 16 -1 (150 2900)(350 2900);
WIRE 16 -1 (350 2900)(350 2975);
WIRE 16 -1 (1050 3500)(1250 3500);
WIRE 16 -1 (1050 3450)(1050 3500);
WIRE 16 -1 (1050 3450)(1250 3450);
WIRE 16 -1 (1050 3400)(1050 3450);
WIRE 16 -1 (1050 3400)(1250 3400);
WIRE 16 -1 (1050 3350)(1050 3400);
WIRE 16 -1 (1050 3350)(1250 3350);
WIRE 16 -1 (1050 3300)(1050 3350);
WIRE 16 -1 (1050 3300)(1250 3300);
WIRE 16 -1 (1050 3250)(1050 3300);
WIRE 16 -1 (1050 3250)(1250 3250);
WIRE 16 -1 (1050 3200)(1050 3250);
WIRE 16 -1 (1050 3200)(1250 3200);
WIRE 16 -1 (1050 3150)(1050 3200);
WIRE 16 -1 (1050 3150)(1250 3150);
WIRE 16 -1 (1050 3100)(1050 3150);
WIRE 16 -1 (1050 3100)(1250 3100);
WIRE 16 -1 (1050 3050)(1050 3100);
WIRE 16 -1 (1050 3050)(1250 3050);
WIRE 16 -1 (1050 3000)(1050 3050);
WIRE 16 -1 (1050 3000)(1250 3000);
WIRE 16 -1 (1050 2950)(1050 3000);
WIRE 16 -1 (1050 2950)(1250 2950);
WIRE 16 -1 (1050 2900)(1050 2950);
WIRE 16 -1 (1050 2900)(1250 2900);
WIRE 16 -1 (1050 2850)(1050 2900);
WIRE 16 -1 (1050 2850)(1250 2850);
WIRE 16 -1 (1050 2800)(1050 2850);
WIRE 16 -1 (1050 2800)(1250 2800);
WIRE 16 -1 (1050 2750)(1050 2800);
WIRE 16 -1 (1050 2750)(1250 2750);
WIRE 16 -1 (1050 2700)(1050 2750);
WIRE 16 -1 (1050 2700)(1250 2700);
WIRE 16 -1 (1050 2650)(1050 2700);
WIRE 16 -1 (1050 2650)(1250 2650);
WIRE 16 -1 (1050 2600)(1050 2650);
WIRE 16 -1 (1050 2600)(1250 2600);
WIRE 16 -1 (1050 2550)(1050 2600);
WIRE 16 -1 (1050 2550)(1250 2550);
WIRE 16 -1 (1050 2500)(1050 2550);
WIRE 16 -1 (1050 2500)(1250 2500);
WIRE 16 -1 (1050 2450)(1050 2500);
WIRE 16 -1 (1050 2450)(1250 2450);
WIRE 16 -1 (1050 2400)(1050 2450);
WIRE 16 -1 (1050 2400)(1250 2400);
WIRE 16 -1 (1050 2350)(1050 2400);
WIRE 16 -1 (1050 2350)(1250 2350);
WIRE 16 -1 (1050 2300)(1050 2350);
WIRE 16 -1 (1050 2300)(1250 2300);
WIRE 16 -1 (1050 2250)(1050 2300);
WIRE 16 -1 (1050 2250)(1250 2250);
WIRE 16 -1 (1050 2200)(1050 2250);
WIRE 16 -1 (1050 2200)(1250 2200);
WIRE 16 -1 (1050 2150)(1050 2200);
WIRE 16 -1 (1050 2150)(1250 2150);
WIRE 16 -1 (1050 2100)(1050 2150);
WIRE 16 -1 (1050 2100)(1250 2100);
WIRE 16 -1 (1050 2050)(1050 2100);
WIRE 16 -1 (1050 2050)(1250 2050);
WIRE 16 -1 (1050 2000)(1050 2050);
WIRE 16 -1 (1050 2000)(1250 2000);
WIRE 16 -1 (1050 1950)(1050 2000);
WIRE 16 -1 (1050 1950)(1250 1950);
WIRE 16 -1 (1050 1900)(1050 1950);
WIRE 16 -1 (1050 1900)(1250 1900);
WIRE 16 -1 (1050 1850)(1050 1900);
WIRE 16 -1 (1050 1850)(1250 1850);
WIRE 16 -1 (1050 1800)(1050 1850);
WIRE 16 -1 (1050 1800)(1250 1800);
WIRE 16 -1 (1050 1750)(1050 1800);
WIRE 16 -1 (1050 1750)(1250 1750);
WIRE 16 -1 (1050 1700)(1050 1750);
WIRE 16 -1 (1050 1700)(1250 1700);
WIRE 16 -1 (1050 1650)(1050 1700);
WIRE 16 -1 (1050 1650)(1250 1650);
WIRE 16 -1 (1050 1600)(1050 1650);
WIRE 16 -1 (1050 1600)(1250 1600);
WIRE 16 -1 (1050 1550)(1050 1600);
WIRE 16 -1 (1050 1550)(1250 1550);
WIRE 16 -1 (1050 1500)(1050 1550);
WIRE 16 -1 (1050 1500)(1250 1500);
WIRE 16 -1 (1050 1450)(1050 1500);
WIRE 16 -1 (1050 1450)(1250 1450);
WIRE 16 -1 (1050 1400)(1050 1450);
WIRE 16 -1 (1050 1400)(1250 1400);
WIRE 16 -1 (1050 1350)(1050 1400);
WIRE 16 -1 (1050 1350)(1250 1350);
WIRE 16 -1 (1050 1300)(1050 1350);
WIRE 16 -1 (1050 1300)(1250 1300);
WIRE 16 -1 (1050 1250)(1050 1300);
WIRE 16 -1 (1050 1250)(1250 1250);
WIRE 16 -1 (1050 1200)(1050 1250);
WIRE 16 -1 (1050 1200)(1250 1200);
WIRE 16 -1 (1050 1100)(1050 1200);
WIRE 16 -1 (-3500 2200)(-3000 2200);
WIRE 16 -1 (-3500 2200)(-3500 2450);
WIRE 16 -1 (-3500 2450)(-4275 2450);
FORCEPROP 2 LAST SIG_NAME FM_DIMM_EVENT_COD_N
J 0
(-4278 2469);
DISPLAY 0.617021 (-4278 2469);
PAINT ORANGE (-4278 2469);
WIRE 16 -1 (-4600 1650)(-4500 1650);
FORCEPROP 2 LAST SIG_NAME M_J_VREF
J 0
(-3800 1660);
DISPLAY 0.617021 (-3800 1660);
PAINT ORANGE (-3800 1660);
WIRE 16 -1 (-4500 1650)(-3000 1650);
WIRE 16 -1 (-4500 1650)(-4500 1550);
WIRE 16 -1 (-3850 1550)(-3000 1550);
FORCEPROP 2 LAST SIG_NAME TP_CH_J_DIMM_J1_RFU_2
J 0
(-3800 1560);
DISPLAY 0.617021 (-3800 1560);
PAINT ORANGE (-3800 1560);
FORCEPROP 2 LASTPROP $XRERR UNIQUE?
J 0
(-4090 1550);
DISPLAY 0.638298 (-4090 1550);
PAINT MONO (-4090 1550);
DISPLAY INVISIBLE (-4090 1550);
WIRE 16 -1 (-3850 1450)(-3000 1450);
FORCEPROP 2 LAST SIG_NAME TP_CH_J_DIMM_J1_RFU_0
J 0
(-3800 1460);
DISPLAY 0.617021 (-3800 1460);
PAINT ORANGE (-3800 1460);
FORCEPROP 2 LASTPROP $XRERR UNIQUE?
J 0
(-4090 1450);
DISPLAY 0.638298 (-4090 1450);
PAINT MONO (-4090 1450);
DISPLAY INVISIBLE (-4090 1450);
WIRE 16 -1 (-3850 1500)(-3000 1500);
FORCEPROP 2 LAST SIG_NAME TP_CH_J_DIMM_J1_RFU_1
J 0
(-3800 1510);
DISPLAY 0.617021 (-3800 1510);
PAINT ORANGE (-3800 1510);
FORCEPROP 2 LASTPROP $XRERR UNIQUE?
J 0
(-4090 1500);
DISPLAY 0.638298 (-4090 1500);
PAINT MONO (-4090 1500);
DISPLAY INVISIBLE (-4090 1500);
WIRE 16 -1 (-3850 1750)(-3000 1750);
FORCEPROP 2 LAST SIG_NAME SMB_DDR_GHJ_VPP_SCL
J 0
(-3810 1760);
DISPLAY 0.617021 (-3810 1760);
PAINT ORANGE (-3810 1760);
WIRE 16 -1 (-3850 1800)(-3000 1800);
WIRE 16 -1 (-3850 1350)(-3000 1350);
FORCEPROP 2 LAST SIG_NAME FM_ADR_COMPLETE_GHJ_N
J 0
(-3800 1360);
DISPLAY 0.617021 (-3800 1360);
PAINT ORANGE (-3800 1360);
WIRE 16 -1 (-3000 2300)(-3400 2300);
WIRE 16 -1 (-3400 2300)(-3400 2750);
WIRE 16 -1 (-3400 2750)(-3850 2750);
FORCEPROP 2 LAST SIG_NAME M_J_PAR
J 0
(-3825 2760);
DISPLAY 0.617021 (-3825 2760);
PAINT ORANGE (-3825 2760);
WIRE 16 -1 (-3000 2250)(-3450 2250);
WIRE 16 -1 (-3450 2250)(-3450 2700);
WIRE 16 -1 (-3450 2700)(-3850 2700);
FORCEPROP 2 LAST SIG_NAME M_GHJ_RST_N
J 0
(-3825 2710);
DISPLAY 0.617021 (-3825 2710);
PAINT ORANGE (-3825 2710);
WIRE 16 -1 (-3300 3350)(-3000 3350);
WIRE 16 -1 (-3300 3400)(-3300 3350);
WIRE 16 -1 (-3300 3400)(-3850 3400);
FORCEPROP 2 LAST SIG_NAME M_J_C<2>
J 0
(-3825 3410);
DISPLAY 0.617021 (-3825 3410);
PAINT ORANGE (-3825 3410);
WIRE 16 -1 (-3000 3850)(-3200 3850);
WIRE 16 -1 (-3000 3500)(-3200 3500);
WIRE 16 -1 (-3000 3300)(-3250 3300);
WIRE 16 -1 (-3000 3250)(-3250 3250);
WIRE 16 -1 (-3000 3200)(-3250 3200);
WIRE 16 -1 (-3000 3950)(-3200 3950);
WIRE 16 -1 (-3000 4000)(-3200 4000);
WIRE 16 -1 (-3000 2700)(-3250 2700);
WIRE 16 -1 (-3000 2650)(-3250 2650);
WIRE 16 -1 (-3000 2600)(-3250 2600);
WIRE 16 -1 (-3000 2550)(-3250 2550);
WIRE 16 -1 (-3000 2500)(-3250 2500);
WIRE 16 -1 (-3000 2450)(-3250 2450);
WIRE 16 -1 (-3000 2400)(-3250 2400);
WIRE 16 -1 (-3000 3050)(-3250 3050);
WIRE 16 -1 (-3000 3600)(-3200 3600);
WIRE 16 -1 (-3000 3700)(-3200 3700);
WIRE 16 -1 (-3000 3750)(-3200 3750);
WIRE 16 -1 (-3000 3800)(-3200 3800);
WIRE 16 -1 (-3000 4050)(-3200 4050);
WIRE 16 -1 (-3000 2750)(-3250 2750);
WIRE 16 -1 (-3000 2850)(-3250 2850);
WIRE 16 -1 (-3000 2900)(-3250 2900);
WIRE 16 -1 (-3000 3000)(-3250 3000);
WIRE 16 -1 (-3000 3150)(-3250 3150);
WIRE 16 -1 (-3000 3450)(-3400 3450);
WIRE 16 -1 (-3000 3550)(-3400 3550);
WIRE 16 -1 (-3000 2100)(-4050 2100);
FORCEPROP 2 LAST SIG_NAME M_J_ACT_N
J 0
(-4000 2110);
DISPLAY 0.617021 (-4000 2110);
PAINT ORANGE (-4000 2110);
WIRE 16 -1 (-3000 2150)(-4075 2150);
FORCEPROP 2 LAST SIG_NAME M_J_ALERT_N
J 0
(-4025 2160);
DISPLAY 0.617021 (-4025 2160);
PAINT ORANGE (-4025 2160);
WIRE 16 -1 (-1800 1700)(-2000 1700);
WIRE 16 -1 (-1800 1750)(-2000 1750);
WIRE 16 -1 (-1800 1650)(-2000 1650);
WIRE 16 -1 (-1800 2000)(-2000 2000);
WIRE 16 -1 (-1800 1950)(-2000 1950);
WIRE 16 -1 (-1800 1800)(-2000 1800);
WIRE 16 -1 (-1800 1850)(-2000 1850);
WIRE 16 -1 (-1800 1900)(-2000 1900);
WIRE 16 -1 (-1800 2300)(-2000 2300);
WIRE 16 -1 (-1800 2250)(-2000 2250);
WIRE 16 -1 (-1800 2200)(-2000 2200);
WIRE 16 -1 (-1800 2150)(-2000 2150);
WIRE 16 -1 (-1800 2100)(-2000 2100);
WIRE 16 -1 (-1800 2050)(-2000 2050);
WIRE 16 -1 (-1800 2550)(-2000 2550);
WIRE 16 -1 (-1800 2350)(-2000 2350);
WIRE 16 -1 (-1800 2400)(-2000 2400);
WIRE 16 -1 (-1800 2500)(-2000 2500);
WIRE 16 -1 (-1800 2450)(-2000 2450);
WIRE 16 -1 (-1800 2800)(-2000 2800);
WIRE 16 -1 (-1800 2700)(-2000 2700);
WIRE 16 -1 (-1800 2650)(-2000 2650);
WIRE 16 -1 (-1800 2600)(-2000 2600);
WIRE 16 -1 (-1800 2750)(-2000 2750);
WIRE 16 -1 (-1800 3050)(-2000 3050);
WIRE 16 -1 (-1800 2900)(-2000 2900);
WIRE 16 -1 (-1800 2850)(-2000 2850);
WIRE 16 -1 (-1800 3000)(-2000 3000);
WIRE 16 -1 (-1800 2950)(-2000 2950);
WIRE 16 -1 (-1800 3100)(-2000 3100);
WIRE 16 -1 (-1800 3300)(-2000 3300);
WIRE 16 -1 (-1800 3250)(-2000 3250);
WIRE 16 -1 (-1800 3200)(-2000 3200);
WIRE 16 -1 (-1800 3150)(-2000 3150);
WIRE 16 -1 (-1800 3350)(-2000 3350);
WIRE 16 -1 (-1800 3400)(-2000 3400);
WIRE 16 -1 (-1800 3550)(-2000 3550);
WIRE 16 -1 (-1800 3450)(-2000 3450);
WIRE 16 -1 (-1800 3500)(-2000 3500);
WIRE 16 -1 (-1800 3800)(-2000 3800);
WIRE 16 -1 (-1800 3750)(-2000 3750);
WIRE 16 -1 (-1800 3650)(-2000 3650);
WIRE 16 -1 (-1800 3600)(-2000 3600);
WIRE 16 -1 (-1800 3700)(-2000 3700);
WIRE 16 -1 (-1800 3950)(-2000 3950);
WIRE 16 -1 (-1800 3900)(-2000 3900);
WIRE 16 -1 (-1800 3850)(-2000 3850);
WIRE 16 -1 (-1800 4050)(-2000 4050);
WIRE 16 -1 (-1800 4000)(-2000 4000);
WIRE 16 -1 (-3000 4550)(-3200 4550);
WIRE 16 -1 (-3000 4600)(-3200 4600);
WIRE 16 -1 (-3000 4800)(-3200 4800);
WIRE 16 -1 (-3000 4100)(-3200 4100);
WIRE 16 -1 (-3000 4150)(-3200 4150);
WIRE 16 -1 (-3000 4200)(-3200 4200);
WIRE 16 -1 (-3000 4250)(-3200 4250);
WIRE 16 -1 (-3000 4300)(-3200 4300);
WIRE 16 -1 (-3000 4350)(-3200 4350);
WIRE 16 -1 (-3000 4400)(-3200 4400);
WIRE 16 -1 (-3000 4450)(-3200 4450);
WIRE 16 -1 (-3000 4500)(-3200 4500);
WIRE 16 -1 (-3000 4650)(-3200 4650);
WIRE 16 -1 (-3000 4700)(-3200 4700);
WIRE 16 -1 (-3000 4750)(-3200 4750);
WIRE 16 -1 (-1800 4350)(-2000 4350);
WIRE 16 -1 (-1800 4300)(-2000 4300);
WIRE 16 -1 (-1800 4250)(-2000 4250);
WIRE 16 -1 (-1800 4200)(-2000 4200);
WIRE 16 -1 (-1800 4150)(-2000 4150);
WIRE 16 -1 (-1800 4100)(-2000 4100);
WIRE 16 -1 (-1800 4600)(-2000 4600);
WIRE 16 -1 (-1800 4450)(-2000 4450);
WIRE 16 -1 (-1800 4400)(-2000 4400);
WIRE 16 -1 (-1800 4500)(-2000 4500);
WIRE 16 -1 (-1800 4550)(-2000 4550);
WIRE 16 -1 (-1800 4800)(-2000 4800);
WIRE 16 -1 (-1800 4750)(-2000 4750);
WIRE 16 -1 (-1800 4700)(-2000 4700);
WIRE 16 -1 (-1800 4650)(-2000 4650);
WIRE 16 -1 (800 3400)(400 3400);
WIRE 16 -1 (600 3450)(400 3450);
WIRE 16 -1 (800 3500)(400 3500);
WIRE 16 -1 (600 3550)(400 3550);
WIRE 16 -1 (800 3600)(400 3600);
WIRE 16 -1 (600 3650)(400 3650);
WIRE 16 -1 (800 3700)(400 3700);
WIRE 16 -1 (600 3750)(400 3750);
WIRE 16 -1 (800 3800)(400 3800);
WIRE 16 -1 (600 3850)(400 3850);
WIRE 16 -1 (800 3900)(400 3900);
WIRE 16 -1 (600 3950)(400 3950);
WIRE 16 -1 (800 4000)(400 4000);
WIRE 16 -1 (600 4050)(400 4050);
WIRE 16 -1 (800 4400)(400 4400);
WIRE 16 -1 (600 4450)(400 4450);
WIRE 16 -1 (800 4500)(400 4500);
WIRE 16 -1 (600 4550)(400 4550);
WIRE 16 -1 (800 4600)(400 4600);
WIRE 16 -1 (600 4650)(400 4650);
WIRE 16 -1 (800 4700)(400 4700);
WIRE 16 -1 (600 4750)(400 4750);
WIRE 16 -1 (800 4800)(400 4800);
WIRE 16 -1 (600 4850)(400 4850);
WIRE 16 -1 (800 4900)(400 4900);
WIRE 16 -1 (600 4950)(400 4950);
WIRE 16 -1 (800 5000)(400 5000);
WIRE 16 -1 (600 5050)(400 5050);
WIRE 16 -1 (800 5100)(400 5100);
WIRE 16 -1 (800 4100)(400 4100);
WIRE 16 -1 (600 4150)(400 4150);
WIRE 16 -1 (800 4200)(400 4200);
WIRE 16 -1 (600 4250)(400 4250);
WIRE 16 -1 (800 4300)(400 4300);
WIRE 16 -1 (600 4350)(400 4350);
WIRE 16 -1 (600 5150)(400 5150);
DOT 1 (-3150 1950);
DOT 1 (-1000 2100);
DOT 1 (-1000 1900);
DOT 1 (1050 3150);
DOT 1 (1050 3100);
DOT 1 (1050 3050);
DOT 1 (1050 3000);
DOT 1 (1050 2950);
DOT 1 (1050 2550);
DOT 1 (350 2900);
DOT 1 (1050 2450);
DOT 1 (1050 2500);
DOT 1 (-4500 1650);
DOT 1 (1050 1200);
DOT 1 (1050 1250);
DOT 1 (1050 1300);
DOT 1 (1050 1400);
DOT 1 (1050 1350);
DOT 1 (1050 1500);
DOT 1 (1050 1450);
DOT 1 (1050 1550);
DOT 1 (1050 1650);
DOT 1 (1050 1600);
DOT 1 (1050 1700);
DOT 1 (1050 1750);
DOT 1 (1050 1800);
DOT 1 (1050 1900);
DOT 1 (1050 1850);
DOT 1 (1050 1950);
DOT 1 (1050 2000);
DOT 1 (1050 2050);
DOT 1 (1050 2100);
DOT 1 (1050 2150);
DOT 1 (1050 2200);
DOT 1 (1050 2300);
DOT 1 (1050 2250);
DOT 1 (1050 2350);
DOT 1 (1050 2400);
DOT 1 (1050 2600);
DOT 1 (1050 2650);
DOT 1 (1050 2700);
DOT 1 (1050 2800);
DOT 1 (1050 2750);
DOT 1 (1050 2850);
DOT 1 (1050 2900);
DOT 1 (1050 3200);
DOT 1 (1050 3250);
DOT 1 (1050 3300);
DOT 1 (1050 3350);
DOT 1 (1050 3450);
DOT 1 (1050 3400);
DOT 1 (2450 1200);
DOT 1 (2450 1250);
DOT 1 (2450 1300);
DOT 1 (2450 1400);
DOT 1 (2450 1350);
DOT 1 (2450 1500);
DOT 1 (2450 1450);
DOT 1 (2450 1550);
DOT 1 (2450 1650);
DOT 1 (2450 1600);
DOT 1 (2450 1800);
DOT 1 (2450 1900);
DOT 1 (2450 1850);
DOT 1 (2450 2000);
DOT 1 (2450 2050);
DOT 1 (2450 2150);
DOT 1 (2450 2200);
DOT 1 (2450 2100);
DOT 1 (2450 2300);
DOT 1 (2450 2250);
DOT 1 (2450 2350);
DOT 1 (2450 2400);
DOT 1 (2450 2450);
DOT 1 (2450 2550);
DOT 1 (2450 2500);
DOT 1 (2450 2600);
DOT 1 (2450 2650);
DOT 1 (2450 2700);
DOT 1 (2450 2800);
DOT 1 (2450 2750);
DOT 1 (2450 2850);
DOT 1 (2450 2900);
DOT 1 (2450 2950);
DOT 1 (2450 3050);
DOT 1 (2450 3000);
DOT 1 (2450 3100);
DOT 1 (2450 3200);
DOT 1 (2450 3150);
DOT 1 (2450 3250);
DOT 1 (2450 3300);
DOT 1 (2450 3350);
DOT 1 (2450 3450);
DOT 1 (2450 3400);
DOT 1 (-3150 2000);
DOT 1 (-1050 2750);
DOT 1 (-1050 2900);
DOT 1 (-1050 2850);
DOT 1 (-1050 2800);
DOT 1 (-1000 2600);
DOT 1 (-1000 2450);
DOT 1 (-1000 2300);
DOT 1 (-1000 2400);
DOT 1 (-1000 2350);
DOT 1 (-1000 2200);
DOT 1 (-1000 2250);
DOT 1 (-1000 2150);
DOT 1 (-1000 2050);
DOT 1 (-1000 1950);
DOT 1 (-1000 2000);
DOT 1 (-1000 1850);
DOT 1 (-1000 1800);
DOT 1 (-1000 1750);
DOT 1 (-1000 1700);
DOT 1 (-1000 1650);
DOT 1 (-1000 1600);
DOT 1 (-1000 1550);
DOT 1 (-1000 1400);
DOT 1 (-1000 1450);
DOT 1 (-1000 1500);
DOT 1 (-1000 1300);
DOT 1 (-1000 1250);
DOT 1 (-1000 1350);
DOT 1 (2450 1700);
DOT 1 (2450 1950);
DOT 1 (2450 1750);
FORCENOTE
PLACE CAP NEAR DIMM CONNECTOR
(-5288 1052) 0;
DISPLAY LEFT (-5288 1052);
DISPLAY 1.957447 (-5288 1052);
PAINT PURPLE (-5288 1052);
FORCENOTE
SMBUS ADDR: 0XAA
(-5250 900) 0;
DISPLAY LEFT (-5250 900);
DISPLAY 1.957447 (-5250 900);
PAINT PURPLE (-5250 900);
QUIT
